FILE_TYPE = MACRO_DRAWING;
SET COLOR_WIRE YELLOW;
SET COLOR_PROP MONO;
SET COLOR_DOT WHITE;
SET COLOR_ARC YELLOW;
SET COLOR_BODY GREEN;
SET COLOR_NOTE MONO;
SET PROP_DISPLAY VALUE;
SET PAGE_NUMBER P132;
FORCEADD CAP_A..1
(2575 4475);
FORCEPROP 1 LAST LOCATION C3L25
J 0
(2625 4575);
DISPLAY 0.617021 (2625 4575);
PAINT AQUA (2625 4575);
FORCEPROP 1 LAST PART_NUMBER E15431-004
J 0
(2625 4325);
DISPLAY 0.617021 (2625 4325);
PAINT BLUE (2625 4325);
FORCEPROP 1 LAST VALUE 22.0UF
J 0
(2625 4525);
DISPLAY 0.617021 (2625 4525);
PAINT SKYBLUE (2625 4525);
FORCEPROP 1 LAST TOLERANCE 20%
J 0
(2625 4425);
DISPLAY 0.617021 (2625 4425);
PAINT SKYBLUE (2625 4425);
FORCEPROP 1 LAST PACK_TYPE 0603V
J 0
(2625 4275);
DISPLAY 0.617021 (2625 4275);
PAINT SKYBLUE (2625 4275);
FORCEPROP 1 LAST VOLTAGE 4V
J 0
(2625 4475);
DISPLAY 0.617021 (2625 4475);
PAINT SKYBLUE (2625 4475);
FORCEPROP 1 LAST MATERIAL X6S
J 0
(2625 4375);
DISPLAY 0.617021 (2625 4375);
PAINT SKYBLUE (2625 4375);
FORCEPROP 1 LASTPIN (2575 4575) $PN 1
J 0
(2585 4555);
DISPLAY 0.617021 (2585 4555);
PAINT WHITE (2585 4555);
FORCEPROP 1 LASTPIN (2575 4375) $PN 2
J 0
(2585 4355);
DISPLAY 0.617021 (2585 4355);
PAINT WHITE (2585 4355);
FORCEPROP 2 LAST CDS_LOCATION C3L25
J 0
(2625 4575);
DISPLAY 0.617021 (2625 4575);
PAINT AQUA (2625 4575);
DISPLAY INVISIBLE (2625 4575);
FORCEPROP 2 LAST BOM_COST SB
J 0
(2625 4675);
DISPLAY 1.361702 (2625 4675);
PAINT ORANGE (2625 4675);
DISPLAY INVISIBLE (2625 4675);
FORCEPROP 2 LAST CDS_LIB dev_discrete
J 0
(2575 4475);
PAINT ORANGE (2575 4475);
DISPLAY INVISIBLE (2575 4475);
FORCEPROP 2 LAST CDS_SEC 1
J 0
(2625 4675);
DISPLAY 1.361702 (2625 4675);
PAINT ORANGE (2625 4675);
DISPLAY INVISIBLE (2625 4675);
FORCEPROP 2 LAST $SEC 1
J 0
(2625 4675);
DISPLAY 0.914894 (2625 4675);
PAINT MONO (2625 4675);
DISPLAY INVISIBLE (2625 4675);
FORCEPROP 1 LAST PATH I1
J 0
(2625 4625);
DISPLAY 0.978723 (2625 4625);
PAINT WHITE (2625 4625);
DISPLAY INVISIBLE (2625 4625);
FORCEPROP 2 LAST ROOM SB_DECOUPLING
J 0
(2625 4625);
DISPLAY 1.361702 (2625 4625);
PAINT ORANGE (2625 4625);
DISPLAY INVISIBLE (2625 4625);
FORCEADD GND..1
(2050 4150);
FORCEPROP 3 LASTPIN (2050 4200) SIG_NAME GND\g
J 0
(2060 4210);
DISPLAY 0.659574 (2060 4210);
PAINT MONO (2060 4210);
DISPLAY INVISIBLE (2060 4210);
FORCEPROP 1 LAST VOLTAGE 0.0V
J 0
(2005 4107);
DISPLAY 0.340426 (2005 4107);
PAINT SKYBLUE (2005 4107);
DISPLAY INVISIBLE (2005 4107);
FORCEPROP 2 LAST BOM_COST SB
J 0
(2075 4225);
DISPLAY 1.361702 (2075 4225);
PAINT ORANGE (2075 4225);
DISPLAY INVISIBLE (2075 4225);
FORCEPROP 1 LAST SIZE 1B
J 0
(2125 4100);
DISPLAY 1.170213 (2125 4100);
PAINT AQUA (2125 4100);
DISPLAY INVISIBLE (2125 4100);
FORCEPROP 2 LAST CDS_LIB mstr_symbols
J 0
(2050 4150);
PAINT MONO (2050 4150);
DISPLAY INVISIBLE (2050 4150);
FORCEPROP 1 LAST PATH I10
J 0
(2125 4150);
DISPLAY 0.872340 (2125 4150);
PAINT AQUA (2125 4150);
DISPLAY INVISIBLE (2125 4150);
FORCEPROP 2 LAST ROOM SB_DECOUPLING
J 0
(2075 4225);
DISPLAY 1.361702 (2075 4225);
PAINT ORANGE (2075 4225);
DISPLAY INVISIBLE (2075 4225);
FORCEPROP 1 LAST BODY_TYPE PLUMBING
J 0
(2005 4107);
DISPLAY 0.340426 (2005 4107);
PAINT GREEN (2005 4107);
DISPLAY INVISIBLE (2005 4107);
FORCEPROP 1 LAST HDL_POWER GND
J 0
(2050 4300);
DISPLAY 1.170213 (2050 4300);
PAINT GREEN (2050 4300);
DISPLAY INVISIBLE (2050 4300);
FORCEADD CAP_A..1
(2200 3500);
FORCEPROP 1 LAST LOCATION C7A36
J 0
(2250 3600);
DISPLAY 0.617021 (2250 3600);
PAINT AQUA (2250 3600);
FORCEPROP 1 LAST PART_NUMBER E15431-004
J 0
(2250 3350);
DISPLAY 0.617021 (2250 3350);
PAINT BLUE (2250 3350);
FORCEPROP 1 LAST VALUE 22.0UF
J 0
(2250 3550);
DISPLAY 0.617021 (2250 3550);
PAINT SKYBLUE (2250 3550);
FORCEPROP 1 LAST TOLERANCE 20%
J 0
(2250 3450);
DISPLAY 0.617021 (2250 3450);
PAINT SKYBLUE (2250 3450);
FORCEPROP 1 LAST PACK_TYPE 0603V
J 0
(2250 3300);
DISPLAY 0.617021 (2250 3300);
PAINT SKYBLUE (2250 3300);
FORCEPROP 1 LAST VOLTAGE 4V
J 0
(2250 3500);
DISPLAY 0.617021 (2250 3500);
PAINT SKYBLUE (2250 3500);
FORCEPROP 1 LAST MATERIAL X6S
J 0
(2250 3400);
DISPLAY 0.617021 (2250 3400);
PAINT SKYBLUE (2250 3400);
FORCEPROP 2 LAST CDS_LOCATION C7A36
J 0
(2250 3600);
DISPLAY 0.617021 (2250 3600);
PAINT AQUA (2250 3600);
DISPLAY INVISIBLE (2250 3600);
FORCEPROP 2 LAST BOM_COST SB
J 0
(2250 3250);
PAINT MONO (2250 3250);
DISPLAY INVISIBLE (2250 3250);
FORCEPROP 2 LAST CDS_LIB dev_discrete
J 0
(2200 3500);
PAINT ORANGE (2200 3500);
DISPLAY INVISIBLE (2200 3500);
FORCEPROP 2 LAST CDS_SEC 1
J 0
(2250 3700);
DISPLAY 1.361702 (2250 3700);
PAINT ORANGE (2250 3700);
DISPLAY INVISIBLE (2250 3700);
FORCEPROP 2 LAST $SEC 1
J 0
(2250 3700);
DISPLAY 0.914894 (2250 3700);
PAINT MONO (2250 3700);
DISPLAY INVISIBLE (2250 3700);
FORCEPROP 1 LAST PATH I11
J 0
(2250 3650);
DISPLAY 0.978723 (2250 3650);
PAINT WHITE (2250 3650);
DISPLAY INVISIBLE (2250 3650);
FORCEPROP 2 LAST ROOM SB_DECOUPLING
J 0
(2200 3500);
PAINT WHITE (2200 3500);
DISPLAY INVISIBLE (2200 3500);
FORCEPROP 1 LASTPIN (2200 3600) $PN 1
J 0
(2210 3580);
DISPLAY 1.063830 (2210 3580);
PAINT WHITE (2210 3580);
DISPLAY INVISIBLE (2210 3580);
FORCEPROP 1 LASTPIN (2200 3400) $PN 2
J 0
(2210 3380);
DISPLAY 1.063830 (2210 3380);
PAINT WHITE (2210 3380);
DISPLAY INVISIBLE (2210 3380);
FORCEADD CAP_A..1
(1825 3500);
FORCEPROP 1 LAST LOCATION C3N12
J 0
(1875 3600);
DISPLAY 0.617021 (1875 3600);
PAINT AQUA (1875 3600);
FORCEPROP 1 LAST VALUE 22.0UF
J 0
(1875 3550);
DISPLAY 0.617021 (1875 3550);
PAINT SKYBLUE (1875 3550);
FORCEPROP 1 LAST TOLERANCE 20%
J 0
(1875 3450);
DISPLAY 0.617021 (1875 3450);
PAINT SKYBLUE (1875 3450);
FORCEPROP 1 LAST PACK_TYPE 0603V
J 0
(1875 3300);
DISPLAY 0.617021 (1875 3300);
PAINT SKYBLUE (1875 3300);
FORCEPROP 1 LAST VOLTAGE 4V
J 0
(1875 3500);
DISPLAY 0.617021 (1875 3500);
PAINT SKYBLUE (1875 3500);
FORCEPROP 1 LAST MATERIAL X6S
J 0
(1875 3400);
DISPLAY 0.617021 (1875 3400);
PAINT SKYBLUE (1875 3400);
FORCEPROP 1 LAST PART_NUMBER E15431-004
J 0
(1875 3350);
DISPLAY 0.617021 (1875 3350);
PAINT BLUE (1875 3350);
FORCEPROP 2 LAST CDS_LOCATION C3N12
J 0
(1875 3600);
DISPLAY 0.617021 (1875 3600);
PAINT AQUA (1875 3600);
DISPLAY INVISIBLE (1875 3600);
FORCEPROP 2 LAST BOM_COST SB
J 0
(1875 3250);
PAINT MONO (1875 3250);
DISPLAY INVISIBLE (1875 3250);
FORCEPROP 2 LAST CDS_LIB dev_discrete
J 0
(1825 3500);
PAINT ORANGE (1825 3500);
DISPLAY INVISIBLE (1825 3500);
FORCEPROP 2 LAST CDS_SEC 1
J 0
(1875 3700);
DISPLAY 1.361702 (1875 3700);
PAINT ORANGE (1875 3700);
DISPLAY INVISIBLE (1875 3700);
FORCEPROP 2 LAST $SEC 1
J 0
(1875 3700);
DISPLAY 0.914894 (1875 3700);
PAINT MONO (1875 3700);
DISPLAY INVISIBLE (1875 3700);
FORCEPROP 1 LAST PATH I12
J 0
(1875 3650);
DISPLAY 0.978723 (1875 3650);
PAINT WHITE (1875 3650);
DISPLAY INVISIBLE (1875 3650);
FORCEPROP 2 LAST ROOM SB_DECOUPLING
J 0
(1825 3500);
PAINT WHITE (1825 3500);
DISPLAY INVISIBLE (1825 3500);
FORCEPROP 1 LASTPIN (1825 3600) $PN 1
J 0
(1835 3580);
DISPLAY 1.063830 (1835 3580);
PAINT WHITE (1835 3580);
DISPLAY INVISIBLE (1835 3580);
FORCEPROP 1 LASTPIN (1825 3400) $PN 2
J 0
(1835 3380);
DISPLAY 1.063830 (1835 3380);
PAINT WHITE (1835 3380);
DISPLAY INVISIBLE (1835 3380);
FORCEADD CAP_A..1
(1450 3500);
FORCEPROP 1 LAST PART_NUMBER E15431-004
J 0
(1500 3350);
DISPLAY 0.617021 (1500 3350);
PAINT BLUE (1500 3350);
FORCEPROP 1 LAST VALUE 22.0UF
J 0
(1500 3550);
DISPLAY 0.617021 (1500 3550);
PAINT SKYBLUE (1500 3550);
FORCEPROP 1 LAST TOLERANCE 20%
J 0
(1500 3450);
DISPLAY 0.617021 (1500 3450);
PAINT SKYBLUE (1500 3450);
FORCEPROP 1 LAST PACK_TYPE 0603V
J 0
(1500 3300);
DISPLAY 0.617021 (1500 3300);
PAINT SKYBLUE (1500 3300);
FORCEPROP 1 LAST VOLTAGE 4V
J 0
(1500 3500);
DISPLAY 0.617021 (1500 3500);
PAINT SKYBLUE (1500 3500);
FORCEPROP 1 LAST MATERIAL X6S
J 0
(1500 3400);
DISPLAY 0.617021 (1500 3400);
PAINT SKYBLUE (1500 3400);
FORCEPROP 1 LAST LOCATION C3N10
J 0
(1500 3600);
DISPLAY 0.617021 (1500 3600);
PAINT AQUA (1500 3600);
FORCEPROP 2 LAST CDS_LOCATION C3N10
J 0
(1500 3600);
DISPLAY 0.617021 (1500 3600);
PAINT AQUA (1500 3600);
DISPLAY INVISIBLE (1500 3600);
FORCEPROP 2 LAST BOM_COST SB
J 0
(1500 3250);
PAINT MONO (1500 3250);
DISPLAY INVISIBLE (1500 3250);
FORCEPROP 2 LAST CDS_LIB dev_discrete
J 0
(1450 3500);
PAINT ORANGE (1450 3500);
DISPLAY INVISIBLE (1450 3500);
FORCEPROP 2 LAST CDS_SEC 1
J 0
(1500 3700);
DISPLAY 1.361702 (1500 3700);
PAINT ORANGE (1500 3700);
DISPLAY INVISIBLE (1500 3700);
FORCEPROP 2 LAST $SEC 1
J 0
(1500 3700);
DISPLAY 0.914894 (1500 3700);
PAINT MONO (1500 3700);
DISPLAY INVISIBLE (1500 3700);
FORCEPROP 1 LAST PATH I13
J 0
(1500 3650);
DISPLAY 0.978723 (1500 3650);
PAINT WHITE (1500 3650);
DISPLAY INVISIBLE (1500 3650);
FORCEPROP 2 LAST ROOM SB_DECOUPLING
J 0
(1450 3500);
PAINT WHITE (1450 3500);
DISPLAY INVISIBLE (1450 3500);
FORCEPROP 1 LASTPIN (1450 3600) $PN 1
J 0
(1460 3580);
DISPLAY 1.063830 (1460 3580);
PAINT WHITE (1460 3580);
DISPLAY INVISIBLE (1460 3580);
FORCEPROP 1 LASTPIN (1450 3400) $PN 2
J 0
(1460 3380);
DISPLAY 1.063830 (1460 3380);
PAINT WHITE (1460 3380);
DISPLAY INVISIBLE (1460 3380);
FORCEADD PVNN_PCH_STBY..1
(1350 3750);
FORCEPROP 3 LASTPIN (1350 3700) SIG_NAME PVNN_PCH_STBY\g
J 0
(1360 3710);
DISPLAY 0.659574 (1360 3710);
PAINT MONO (1360 3710);
DISPLAY INVISIBLE (1360 3710);
FORCEPROP 1 LAST VOLTAGE 1.0V
J 0
(1305 3707);
DISPLAY 0.340426 (1305 3707);
PAINT SKYBLUE (1305 3707);
DISPLAY INVISIBLE (1305 3707);
FORCEPROP 2 LAST CDS_LIB mstr_symbols
J 0
(1350 3750);
PAINT ORANGE (1350 3750);
DISPLAY INVISIBLE (1350 3750);
FORCEPROP 2 LAST BOM_COST SB
J 0
(1350 3850);
DISPLAY 1.361702 (1350 3850);
PAINT ORANGE (1350 3850);
DISPLAY INVISIBLE (1350 3850);
FORCEPROP 1 LAST PATH I14
J 0
(1400 3775);
DISPLAY 0.872340 (1400 3775);
PAINT AQUA (1400 3775);
DISPLAY INVISIBLE (1400 3775);
FORCEPROP 2 LAST ROOM SB_DECOUPLING
J 0
(1350 3850);
DISPLAY 1.361702 (1350 3850);
PAINT WHITE (1350 3850);
DISPLAY INVISIBLE (1350 3850);
FORCEPROP 1 LAST BODY_TYPE PLUMBING
J 0
(1305 3707);
DISPLAY 0.340426 (1305 3707);
PAINT GREEN (1305 3707);
DISPLAY INVISIBLE (1305 3707);
FORCEPROP 1 LAST HDL_POWER PVNN_PCH_STBY
J 1
(1350 3800);
DISPLAY 0.872340 (1350 3800);
PAINT GREEN (1350 3800);
DISPLAY INVISIBLE (1350 3800);
FORCEADD GND..1
(2075 3175);
FORCEPROP 3 LASTPIN (2075 3225) SIG_NAME GND\g
J 0
(2085 3235);
DISPLAY 0.659574 (2085 3235);
PAINT MONO (2085 3235);
DISPLAY INVISIBLE (2085 3235);
FORCEPROP 1 LAST VOLTAGE 0
J 0
(2075 3175);
PAINT SKYBLUE (2075 3175);
DISPLAY INVISIBLE (2075 3175);
FORCEPROP 2 LAST CDS_LIB mstr_symbols
J 0
(2075 3175);
PAINT ORANGE (2075 3175);
DISPLAY INVISIBLE (2075 3175);
FORCEPROP 1 LAST SIZE 1B
J 0
(2150 3125);
DISPLAY 1.404255 (2150 3125);
PAINT GREEN (2150 3125);
DISPLAY INVISIBLE (2150 3125);
FORCEPROP 2 LAST BOM_COST SB
J 0
(2025 3250);
PAINT MONO (2025 3250);
DISPLAY INVISIBLE (2025 3250);
FORCEPROP 1 LAST PATH I15
J 0
(2150 3175);
DISPLAY 0.872340 (2150 3175);
PAINT AQUA (2150 3175);
DISPLAY INVISIBLE (2150 3175);
FORCEPROP 2 LAST ROOM SB_DECOUPLING
J 0
(1600 3250);
PAINT WHITE (1600 3250);
DISPLAY INVISIBLE (1600 3250);
FORCEPROP 1 LAST BODY_TYPE PLUMBING
J 0
(2030 3132);
DISPLAY 0.340426 (2030 3132);
PAINT GREEN (2030 3132);
DISPLAY INVISIBLE (2030 3132);
FORCEPROP 1 LAST HDL_POWER GND
J 0
(2075 3325);
DISPLAY 1.404255 (2075 3325);
PAINT GREEN (2075 3325);
DISPLAY INVISIBLE (2075 3325);
FORCEADD CAP_A..1
(1850 2525);
FORCEPROP 1 LAST LOCATION C3N24
J 0
(1900 2625);
DISPLAY 0.617021 (1900 2625);
PAINT AQUA (1900 2625);
FORCEPROP 1 LAST PART_NUMBER E15431-004
J 0
(1900 2375);
DISPLAY 0.617021 (1900 2375);
PAINT BLUE (1900 2375);
FORCEPROP 1 LAST VALUE 22.0UF
J 0
(1900 2575);
DISPLAY 0.617021 (1900 2575);
PAINT SKYBLUE (1900 2575);
FORCEPROP 1 LAST TOLERANCE 20%
J 0
(1900 2475);
DISPLAY 0.617021 (1900 2475);
PAINT SKYBLUE (1900 2475);
FORCEPROP 1 LAST PACK_TYPE 0603V
J 0
(1900 2325);
DISPLAY 0.617021 (1900 2325);
PAINT SKYBLUE (1900 2325);
FORCEPROP 1 LAST VOLTAGE 4V
J 0
(1900 2525);
DISPLAY 0.617021 (1900 2525);
PAINT SKYBLUE (1900 2525);
FORCEPROP 1 LAST MATERIAL X6S
J 0
(1900 2425);
DISPLAY 0.617021 (1900 2425);
PAINT SKYBLUE (1900 2425);
FORCEPROP 2 LAST CDS_LOCATION C3N24
J 0
(1900 2625);
DISPLAY 0.617021 (1900 2625);
PAINT AQUA (1900 2625);
DISPLAY INVISIBLE (1900 2625);
FORCEPROP 2 LAST BOM_COST SB
J 0
(1900 2275);
PAINT MONO (1900 2275);
DISPLAY INVISIBLE (1900 2275);
FORCEPROP 2 LAST CDS_LIB dev_discrete
J 0
(1850 2525);
PAINT ORANGE (1850 2525);
DISPLAY INVISIBLE (1850 2525);
FORCEPROP 2 LAST CDS_SEC 1
J 0
(1900 2725);
DISPLAY 1.361702 (1900 2725);
PAINT ORANGE (1900 2725);
DISPLAY INVISIBLE (1900 2725);
FORCEPROP 2 LAST $SEC 1
J 0
(1900 2725);
DISPLAY 0.914894 (1900 2725);
PAINT MONO (1900 2725);
DISPLAY INVISIBLE (1900 2725);
FORCEPROP 1 LAST PATH I16
J 0
(1900 2675);
DISPLAY 0.978723 (1900 2675);
PAINT WHITE (1900 2675);
DISPLAY INVISIBLE (1900 2675);
FORCEPROP 2 LAST ROOM SB_DECOUPLING
J 0
(1850 2525);
PAINT WHITE (1850 2525);
DISPLAY INVISIBLE (1850 2525);
FORCEPROP 1 LASTPIN (1850 2625) $PN 1
J 0
(1860 2605);
DISPLAY 1.063830 (1860 2605);
PAINT WHITE (1860 2605);
DISPLAY INVISIBLE (1860 2605);
FORCEPROP 1 LASTPIN (1850 2425) $PN 2
J 0
(1860 2405);
DISPLAY 1.063830 (1860 2405);
PAINT WHITE (1860 2405);
DISPLAY INVISIBLE (1860 2405);
FORCEADD CAP_A..1
(1475 2525);
FORCEPROP 1 LAST LOCATION C3N28
J 0
(1525 2625);
DISPLAY 0.617021 (1525 2625);
PAINT AQUA (1525 2625);
FORCEPROP 1 LAST PART_NUMBER E15431-004
J 0
(1525 2375);
DISPLAY 0.617021 (1525 2375);
PAINT BLUE (1525 2375);
FORCEPROP 1 LAST VALUE 22.0UF
J 0
(1525 2575);
DISPLAY 0.617021 (1525 2575);
PAINT SKYBLUE (1525 2575);
FORCEPROP 1 LAST TOLERANCE 20%
J 0
(1525 2475);
DISPLAY 0.617021 (1525 2475);
PAINT SKYBLUE (1525 2475);
FORCEPROP 1 LAST PACK_TYPE 0603V
J 0
(1525 2325);
DISPLAY 0.617021 (1525 2325);
PAINT SKYBLUE (1525 2325);
FORCEPROP 1 LAST VOLTAGE 4V
J 0
(1525 2525);
DISPLAY 0.617021 (1525 2525);
PAINT SKYBLUE (1525 2525);
FORCEPROP 1 LAST MATERIAL X6S
J 0
(1525 2425);
DISPLAY 0.617021 (1525 2425);
PAINT SKYBLUE (1525 2425);
FORCEPROP 2 LAST CDS_LOCATION C3N28
J 0
(1525 2625);
DISPLAY 0.617021 (1525 2625);
PAINT AQUA (1525 2625);
DISPLAY INVISIBLE (1525 2625);
FORCEPROP 2 LAST BOM_COST SB
J 0
(1525 2275);
PAINT MONO (1525 2275);
DISPLAY INVISIBLE (1525 2275);
FORCEPROP 2 LAST CDS_LIB dev_discrete
J 0
(1475 2525);
PAINT ORANGE (1475 2525);
DISPLAY INVISIBLE (1475 2525);
FORCEPROP 2 LAST CDS_SEC 1
J 0
(1525 2725);
DISPLAY 1.361702 (1525 2725);
PAINT ORANGE (1525 2725);
DISPLAY INVISIBLE (1525 2725);
FORCEPROP 2 LAST $SEC 1
J 0
(1525 2725);
DISPLAY 0.914894 (1525 2725);
PAINT MONO (1525 2725);
DISPLAY INVISIBLE (1525 2725);
FORCEPROP 1 LAST PATH I17
J 0
(1525 2675);
DISPLAY 0.978723 (1525 2675);
PAINT WHITE (1525 2675);
DISPLAY INVISIBLE (1525 2675);
FORCEPROP 2 LAST ROOM SB_DECOUPLING
J 0
(1475 2525);
PAINT WHITE (1475 2525);
DISPLAY INVISIBLE (1475 2525);
FORCEPROP 1 LASTPIN (1475 2625) $PN 1
J 0
(1485 2605);
DISPLAY 1.063830 (1485 2605);
PAINT WHITE (1485 2605);
DISPLAY INVISIBLE (1485 2605);
FORCEPROP 1 LASTPIN (1475 2425) $PN 2
J 0
(1485 2405);
DISPLAY 1.063830 (1485 2405);
PAINT WHITE (1485 2405);
DISPLAY INVISIBLE (1485 2405);
FORCEADD PVNN_PCH_STBY..1
(1400 2775);
FORCEPROP 3 LASTPIN (1400 2725) SIG_NAME PVNN_PCH_STBY\g
J 0
(1410 2735);
DISPLAY 0.659574 (1410 2735);
PAINT MONO (1410 2735);
DISPLAY INVISIBLE (1410 2735);
FORCEPROP 1 LAST VOLTAGE 1.0V
J 0
(1355 2732);
DISPLAY 0.340426 (1355 2732);
PAINT SKYBLUE (1355 2732);
DISPLAY INVISIBLE (1355 2732);
FORCEPROP 2 LAST CDS_LIB mstr_symbols
J 0
(1400 2775);
PAINT ORANGE (1400 2775);
DISPLAY INVISIBLE (1400 2775);
FORCEPROP 2 LAST BOM_COST SB
J 0
(1400 2875);
DISPLAY 1.361702 (1400 2875);
PAINT ORANGE (1400 2875);
DISPLAY INVISIBLE (1400 2875);
FORCEPROP 1 LAST PATH I18
J 0
(1450 2800);
DISPLAY 0.872340 (1450 2800);
PAINT AQUA (1450 2800);
DISPLAY INVISIBLE (1450 2800);
FORCEPROP 2 LAST ROOM SB_DECOUPLING
J 0
(1400 2875);
DISPLAY 1.361702 (1400 2875);
PAINT WHITE (1400 2875);
DISPLAY INVISIBLE (1400 2875);
FORCEPROP 1 LAST BODY_TYPE PLUMBING
J 0
(1355 2732);
DISPLAY 0.340426 (1355 2732);
PAINT GREEN (1355 2732);
DISPLAY INVISIBLE (1355 2732);
FORCEPROP 1 LAST HDL_POWER PVNN_PCH_STBY
J 1
(1400 2825);
DISPLAY 0.872340 (1400 2825);
PAINT GREEN (1400 2825);
DISPLAY INVISIBLE (1400 2825);
FORCEADD CAP_A..1
(1075 3500);
FORCEPROP 1 LAST LOCATION C3N11
J 0
(1125 3600);
DISPLAY 0.617021 (1125 3600);
PAINT AQUA (1125 3600);
FORCEPROP 1 LAST PART_NUMBER E15431-004
J 0
(1125 3350);
DISPLAY 0.617021 (1125 3350);
PAINT BLUE (1125 3350);
FORCEPROP 1 LAST VALUE 22.0UF
J 0
(1125 3550);
DISPLAY 0.617021 (1125 3550);
PAINT SKYBLUE (1125 3550);
FORCEPROP 1 LAST TOLERANCE 20%
J 0
(1125 3450);
DISPLAY 0.617021 (1125 3450);
PAINT SKYBLUE (1125 3450);
FORCEPROP 1 LAST PACK_TYPE 0603V
J 0
(1125 3300);
DISPLAY 0.617021 (1125 3300);
PAINT SKYBLUE (1125 3300);
FORCEPROP 1 LAST VOLTAGE 4V
J 0
(1125 3500);
DISPLAY 0.617021 (1125 3500);
PAINT SKYBLUE (1125 3500);
FORCEPROP 1 LAST MATERIAL X6S
J 0
(1125 3400);
DISPLAY 0.617021 (1125 3400);
PAINT SKYBLUE (1125 3400);
FORCEPROP 2 LAST CDS_LOCATION C3N11
J 0
(1125 3600);
DISPLAY 0.617021 (1125 3600);
PAINT AQUA (1125 3600);
DISPLAY INVISIBLE (1125 3600);
FORCEPROP 2 LAST BOM_COST SB
J 0
(1125 3250);
PAINT MONO (1125 3250);
DISPLAY INVISIBLE (1125 3250);
FORCEPROP 2 LAST CDS_LIB dev_discrete
J 0
(1075 3500);
PAINT ORANGE (1075 3500);
DISPLAY INVISIBLE (1075 3500);
FORCEPROP 2 LAST CDS_SEC 1
J 0
(1125 3700);
DISPLAY 1.361702 (1125 3700);
PAINT ORANGE (1125 3700);
DISPLAY INVISIBLE (1125 3700);
FORCEPROP 2 LAST $SEC 1
J 0
(1125 3700);
DISPLAY 0.914894 (1125 3700);
PAINT MONO (1125 3700);
DISPLAY INVISIBLE (1125 3700);
FORCEPROP 1 LAST PATH I19
J 0
(1125 3650);
DISPLAY 0.978723 (1125 3650);
PAINT WHITE (1125 3650);
DISPLAY INVISIBLE (1125 3650);
FORCEPROP 2 LAST ROOM SB_DECOUPLING
J 0
(1075 3500);
PAINT WHITE (1075 3500);
DISPLAY INVISIBLE (1075 3500);
FORCEPROP 1 LASTPIN (1075 3600) $PN 1
J 0
(1085 3580);
DISPLAY 1.063830 (1085 3580);
PAINT WHITE (1085 3580);
DISPLAY INVISIBLE (1085 3580);
FORCEPROP 1 LASTPIN (1075 3400) $PN 2
J 0
(1085 3380);
DISPLAY 1.063830 (1085 3380);
PAINT WHITE (1085 3380);
DISPLAY INVISIBLE (1085 3380);
FORCEADD CAP_A..1
(2200 4475);
FORCEPROP 1 LAST LOCATION C3M7
J 0
(2250 4575);
DISPLAY 0.617021 (2250 4575);
PAINT AQUA (2250 4575);
FORCEPROP 1 LAST PART_NUMBER E15431-004
J 0
(2250 4325);
DISPLAY 0.617021 (2250 4325);
PAINT BLUE (2250 4325);
FORCEPROP 1 LAST VALUE 22.0UF
J 0
(2250 4525);
DISPLAY 0.617021 (2250 4525);
PAINT SKYBLUE (2250 4525);
FORCEPROP 1 LAST TOLERANCE 20%
J 0
(2250 4425);
DISPLAY 0.617021 (2250 4425);
PAINT SKYBLUE (2250 4425);
FORCEPROP 1 LAST PACK_TYPE 0603V
J 0
(2250 4275);
DISPLAY 0.617021 (2250 4275);
PAINT SKYBLUE (2250 4275);
FORCEPROP 1 LAST VOLTAGE 4V
J 0
(2250 4475);
DISPLAY 0.617021 (2250 4475);
PAINT SKYBLUE (2250 4475);
FORCEPROP 1 LAST MATERIAL X6S
J 0
(2250 4375);
DISPLAY 0.617021 (2250 4375);
PAINT SKYBLUE (2250 4375);
FORCEPROP 1 LASTPIN (2200 4575) $PN 1
J 0
(2210 4555);
DISPLAY 0.617021 (2210 4555);
PAINT WHITE (2210 4555);
FORCEPROP 1 LASTPIN (2200 4375) $PN 2
J 0
(2210 4355);
DISPLAY 0.617021 (2210 4355);
PAINT WHITE (2210 4355);
FORCEPROP 2 LAST CDS_LOCATION C3M7
J 0
(2250 4575);
DISPLAY 0.617021 (2250 4575);
PAINT AQUA (2250 4575);
DISPLAY INVISIBLE (2250 4575);
FORCEPROP 2 LAST BOM_COST SB
J 0
(2250 4675);
DISPLAY 1.361702 (2250 4675);
PAINT ORANGE (2250 4675);
DISPLAY INVISIBLE (2250 4675);
FORCEPROP 2 LAST CDS_LIB dev_discrete
J 0
(2200 4475);
PAINT ORANGE (2200 4475);
DISPLAY INVISIBLE (2200 4475);
FORCEPROP 2 LAST CDS_SEC 1
J 0
(2250 4675);
DISPLAY 1.361702 (2250 4675);
PAINT ORANGE (2250 4675);
DISPLAY INVISIBLE (2250 4675);
FORCEPROP 2 LAST $SEC 1
J 0
(2250 4675);
DISPLAY 0.914894 (2250 4675);
PAINT MONO (2250 4675);
DISPLAY INVISIBLE (2250 4675);
FORCEPROP 1 LAST PATH I2
J 0
(2250 4625);
DISPLAY 0.978723 (2250 4625);
PAINT WHITE (2250 4625);
DISPLAY INVISIBLE (2250 4625);
FORCEPROP 2 LAST ROOM SB_DECOUPLING
J 0
(2250 4625);
DISPLAY 1.361702 (2250 4625);
PAINT ORANGE (2250 4625);
DISPLAY INVISIBLE (2250 4625);
FORCEADD CAP_A..1
(1100 2525);
FORCEPROP 1 LAST LOCATION C3N31
J 0
(1150 2625);
DISPLAY 0.617021 (1150 2625);
PAINT AQUA (1150 2625);
FORCEPROP 1 LAST PART_NUMBER E15431-004
J 0
(1150 2375);
DISPLAY 0.617021 (1150 2375);
PAINT BLUE (1150 2375);
FORCEPROP 1 LAST VALUE 22.0UF
J 0
(1150 2575);
DISPLAY 0.617021 (1150 2575);
PAINT SKYBLUE (1150 2575);
FORCEPROP 1 LAST TOLERANCE 20%
J 0
(1150 2475);
DISPLAY 0.617021 (1150 2475);
PAINT SKYBLUE (1150 2475);
FORCEPROP 1 LAST PACK_TYPE 0603V
J 0
(1150 2325);
DISPLAY 0.617021 (1150 2325);
PAINT SKYBLUE (1150 2325);
FORCEPROP 1 LAST VOLTAGE 4V
J 0
(1150 2525);
DISPLAY 0.617021 (1150 2525);
PAINT SKYBLUE (1150 2525);
FORCEPROP 1 LAST MATERIAL X6S
J 0
(1150 2425);
DISPLAY 0.617021 (1150 2425);
PAINT SKYBLUE (1150 2425);
FORCEPROP 2 LAST CDS_LOCATION C3N31
J 0
(1150 2625);
DISPLAY 0.617021 (1150 2625);
PAINT AQUA (1150 2625);
DISPLAY INVISIBLE (1150 2625);
FORCEPROP 2 LAST BOM_COST SB
J 0
(1150 2275);
PAINT MONO (1150 2275);
DISPLAY INVISIBLE (1150 2275);
FORCEPROP 2 LAST CDS_LIB dev_discrete
J 0
(1100 2525);
PAINT ORANGE (1100 2525);
DISPLAY INVISIBLE (1100 2525);
FORCEPROP 2 LAST CDS_SEC 1
J 0
(1150 2725);
DISPLAY 1.361702 (1150 2725);
PAINT ORANGE (1150 2725);
DISPLAY INVISIBLE (1150 2725);
FORCEPROP 2 LAST $SEC 1
J 0
(1150 2725);
DISPLAY 0.914894 (1150 2725);
PAINT MONO (1150 2725);
DISPLAY INVISIBLE (1150 2725);
FORCEPROP 1 LAST PATH I20
J 0
(1150 2675);
DISPLAY 0.978723 (1150 2675);
PAINT WHITE (1150 2675);
DISPLAY INVISIBLE (1150 2675);
FORCEPROP 2 LAST ROOM SB_DECOUPLING
J 0
(1100 2525);
PAINT WHITE (1100 2525);
DISPLAY INVISIBLE (1100 2525);
FORCEPROP 1 LASTPIN (1100 2625) $PN 1
J 0
(1110 2605);
DISPLAY 1.063830 (1110 2605);
PAINT WHITE (1110 2605);
DISPLAY INVISIBLE (1110 2605);
FORCEPROP 1 LASTPIN (1100 2425) $PN 2
J 0
(1110 2405);
DISPLAY 1.063830 (1110 2405);
PAINT WHITE (1110 2405);
DISPLAY INVISIBLE (1110 2405);
FORCEADD GND..1
(2050 2200);
FORCEPROP 3 LASTPIN (2050 2250) SIG_NAME GND\g
J 0
(2060 2260);
DISPLAY 0.659574 (2060 2260);
PAINT MONO (2060 2260);
DISPLAY INVISIBLE (2060 2260);
FORCEPROP 1 LAST VOLTAGE 0
J 0
(2050 2200);
PAINT SKYBLUE (2050 2200);
DISPLAY INVISIBLE (2050 2200);
FORCEPROP 2 LAST BOM_COST SB
J 0
(2000 2275);
PAINT MONO (2000 2275);
DISPLAY INVISIBLE (2000 2275);
FORCEPROP 2 LAST CDS_LIB mstr_symbols
J 0
(2050 2200);
PAINT ORANGE (2050 2200);
DISPLAY INVISIBLE (2050 2200);
FORCEPROP 1 LAST SIZE 1B
J 0
(2125 2150);
DISPLAY 1.404255 (2125 2150);
PAINT GREEN (2125 2150);
DISPLAY INVISIBLE (2125 2150);
FORCEPROP 1 LAST PATH I21
J 0
(2125 2200);
DISPLAY 0.872340 (2125 2200);
PAINT AQUA (2125 2200);
DISPLAY INVISIBLE (2125 2200);
FORCEPROP 2 LAST ROOM SB_DECOUPLING
J 0
(1575 2275);
PAINT WHITE (1575 2275);
DISPLAY INVISIBLE (1575 2275);
FORCEPROP 1 LAST BODY_TYPE PLUMBING
J 0
(2005 2157);
DISPLAY 0.340426 (2005 2157);
PAINT GREEN (2005 2157);
DISPLAY INVISIBLE (2005 2157);
FORCEPROP 1 LAST HDL_POWER GND
J 0
(2050 2350);
DISPLAY 1.404255 (2050 2350);
PAINT GREEN (2050 2350);
DISPLAY INVISIBLE (2050 2350);
FORCEADD PVNN_PCH_STBY..1
(1925 1875);
FORCEPROP 3 LASTPIN (1925 1825) SIG_NAME PVNN_PCH_STBY\g
J 0
(1935 1835);
DISPLAY 0.659574 (1935 1835);
PAINT MONO (1935 1835);
DISPLAY INVISIBLE (1935 1835);
FORCEPROP 1 LAST VOLTAGE 1.0V
J 0
(1880 1832);
DISPLAY 0.340426 (1880 1832);
PAINT SKYBLUE (1880 1832);
DISPLAY INVISIBLE (1880 1832);
FORCEPROP 2 LAST CDS_LIB mstr_symbols
J 0
(1925 1875);
PAINT ORANGE (1925 1875);
DISPLAY INVISIBLE (1925 1875);
FORCEPROP 2 LAST BOM_COST SB
J 0
(1925 1975);
DISPLAY 1.361702 (1925 1975);
PAINT ORANGE (1925 1975);
DISPLAY INVISIBLE (1925 1975);
FORCEPROP 1 LAST PATH I22
J 0
(1975 1900);
DISPLAY 0.872340 (1975 1900);
PAINT AQUA (1975 1900);
DISPLAY INVISIBLE (1975 1900);
FORCEPROP 2 LAST ROOM SB_DECOUPLING
J 0
(1925 1975);
DISPLAY 1.361702 (1925 1975);
PAINT ORANGE (1925 1975);
DISPLAY INVISIBLE (1925 1975);
FORCEPROP 1 LAST BODY_TYPE PLUMBING
J 0
(1880 1832);
DISPLAY 0.340426 (1880 1832);
PAINT GREEN (1880 1832);
DISPLAY INVISIBLE (1880 1832);
FORCEPROP 1 LAST HDL_POWER PVNN_PCH_STBY
J 1
(1925 1925);
DISPLAY 0.872340 (1925 1925);
PAINT GREEN (1925 1925);
DISPLAY INVISIBLE (1925 1925);
FORCEADD CAP..1
(2150 1575);
FORCEPROP 1 LAST LOCATION C7A33
J 0
(2200 1675);
DISPLAY 0.617021 (2200 1675);
PAINT AQUA (2200 1675);
FORCEPROP 1 LAST PART_NUMBER C95333-006
J 0
(2200 1425);
DISPLAY 0.617021 (2200 1425);
PAINT BLUE (2200 1425);
FORCEPROP 1 LAST VALUE 47UF
J 0
(2200 1625);
DISPLAY 0.617021 (2200 1625);
PAINT SKYBLUE (2200 1625);
FORCEPROP 1 LAST TOLERANCE 20%
J 0
(2200 1525);
DISPLAY 0.617021 (2200 1525);
PAINT SKYBLUE (2200 1525);
FORCEPROP 1 LAST PACK_TYPE 0805
J 0
(2200 1375);
DISPLAY 0.617021 (2200 1375);
PAINT SKYBLUE (2200 1375);
FORCEPROP 1 LAST VOLTAGE 4V
J 0
(2200 1575);
DISPLAY 0.617021 (2200 1575);
PAINT SKYBLUE (2200 1575);
FORCEPROP 1 LAST MATERIAL X6S
J 0
(2200 1475);
DISPLAY 0.617021 (2200 1475);
PAINT SKYBLUE (2200 1475);
FORCEPROP 1 LASTPIN (2150 1475) $PN 2
J 0
(2160 1455);
DISPLAY 0.617021 (2160 1455);
PAINT WHITE (2160 1455);
FORCEPROP 1 LASTPIN (2150 1675) $PN 1
J 0
(2160 1655);
DISPLAY 0.617021 (2160 1655);
PAINT WHITE (2160 1655);
FORCEPROP 2 LAST CDS_LIB mstr_discrete
J 0
(2150 1575);
PAINT MONO (2150 1575);
DISPLAY INVISIBLE (2150 1575);
FORCEPROP 2 LAST BOM_COST SB
J 0
(2200 1775);
DISPLAY 1.361702 (2200 1775);
PAINT ORANGE (2200 1775);
DISPLAY INVISIBLE (2200 1775);
FORCEPROP 2 LAST CDS_SEC 1
J 0
(2200 1775);
DISPLAY 1.361702 (2200 1775);
PAINT ORANGE (2200 1775);
DISPLAY INVISIBLE (2200 1775);
FORCEPROP 2 LAST $SEC 1
J 0
(2200 1775);
DISPLAY 0.914894 (2200 1775);
PAINT MONO (2200 1775);
DISPLAY INVISIBLE (2200 1775);
FORCEPROP 2 LAST CDS_LOCATION C7A33
J 0
(2200 1675);
DISPLAY 0.617021 (2200 1675);
PAINT AQUA (2200 1675);
DISPLAY INVISIBLE (2200 1675);
FORCEPROP 1 LAST PATH I23
J 0
(2200 1725);
DISPLAY 0.978723 (2200 1725);
PAINT WHITE (2200 1725);
DISPLAY INVISIBLE (2200 1725);
FORCEPROP 2 LAST ROOM SB_DECOUPLING
J 0
(2200 1725);
DISPLAY 1.361702 (2200 1725);
PAINT ORANGE (2200 1725);
DISPLAY INVISIBLE (2200 1725);
FORCEADD CAP..1
(1700 1575);
FORCEPROP 1 LAST LOCATION C7B4
J 0
(1750 1675);
DISPLAY 0.617021 (1750 1675);
PAINT AQUA (1750 1675);
FORCEPROP 1 LAST PART_NUMBER C95333-006
J 0
(1750 1425);
DISPLAY 0.617021 (1750 1425);
PAINT BLUE (1750 1425);
FORCEPROP 1 LAST VALUE 47UF
J 0
(1750 1625);
DISPLAY 0.617021 (1750 1625);
PAINT SKYBLUE (1750 1625);
FORCEPROP 1 LAST TOLERANCE 20%
J 0
(1750 1525);
DISPLAY 0.617021 (1750 1525);
PAINT SKYBLUE (1750 1525);
FORCEPROP 1 LAST PACK_TYPE 0805
J 0
(1750 1375);
DISPLAY 0.617021 (1750 1375);
PAINT SKYBLUE (1750 1375);
FORCEPROP 1 LAST VOLTAGE 4V
J 0
(1750 1575);
DISPLAY 0.617021 (1750 1575);
PAINT SKYBLUE (1750 1575);
FORCEPROP 1 LAST MATERIAL X6S
J 0
(1750 1475);
DISPLAY 0.617021 (1750 1475);
PAINT SKYBLUE (1750 1475);
FORCEPROP 1 LASTPIN (1700 1475) $PN 2
J 0
(1710 1455);
DISPLAY 0.617021 (1710 1455);
PAINT WHITE (1710 1455);
FORCEPROP 1 LASTPIN (1700 1675) $PN 1
J 0
(1710 1655);
DISPLAY 0.617021 (1710 1655);
PAINT WHITE (1710 1655);
FORCEPROP 2 LAST CDS_LIB mstr_discrete
J 0
(1700 1575);
PAINT MONO (1700 1575);
DISPLAY INVISIBLE (1700 1575);
FORCEPROP 2 LAST BOM_COST SB
J 0
(1750 1775);
DISPLAY 1.361702 (1750 1775);
PAINT ORANGE (1750 1775);
DISPLAY INVISIBLE (1750 1775);
FORCEPROP 2 LAST CDS_SEC 1
J 0
(1750 1775);
DISPLAY 1.361702 (1750 1775);
PAINT ORANGE (1750 1775);
DISPLAY INVISIBLE (1750 1775);
FORCEPROP 2 LAST $SEC 1
J 0
(1750 1775);
DISPLAY 0.914894 (1750 1775);
PAINT MONO (1750 1775);
DISPLAY INVISIBLE (1750 1775);
FORCEPROP 2 LAST CDS_LOCATION C7B4
J 0
(1750 1675);
DISPLAY 0.617021 (1750 1675);
PAINT AQUA (1750 1675);
DISPLAY INVISIBLE (1750 1675);
FORCEPROP 1 LAST PATH I24
J 0
(1750 1725);
DISPLAY 0.978723 (1750 1725);
PAINT WHITE (1750 1725);
DISPLAY INVISIBLE (1750 1725);
FORCEPROP 2 LAST ROOM SB_DECOUPLING
J 0
(1750 1725);
DISPLAY 1.361702 (1750 1725);
PAINT ORANGE (1750 1725);
DISPLAY INVISIBLE (1750 1725);
FORCEADD GND..1
(1925 1200);
FORCEPROP 3 LASTPIN (1925 1250) SIG_NAME GND\g
J 0
(1935 1260);
DISPLAY 0.659574 (1935 1260);
PAINT MONO (1935 1260);
DISPLAY INVISIBLE (1935 1260);
FORCEPROP 1 LAST VOLTAGE 0.0V
J 0
(1880 1157);
DISPLAY 0.340426 (1880 1157);
PAINT SKYBLUE (1880 1157);
DISPLAY INVISIBLE (1880 1157);
FORCEPROP 2 LAST BOM_COST SB
J 0
(1950 1275);
DISPLAY 1.361702 (1950 1275);
PAINT ORANGE (1950 1275);
DISPLAY INVISIBLE (1950 1275);
FORCEPROP 2 LAST CDS_LIB mstr_symbols
J 0
(1925 1200);
PAINT MONO (1925 1200);
DISPLAY INVISIBLE (1925 1200);
FORCEPROP 1 LAST SIZE 1B
J 0
(2000 1150);
DISPLAY 1.170213 (2000 1150);
PAINT AQUA (2000 1150);
DISPLAY INVISIBLE (2000 1150);
FORCEPROP 1 LAST PATH I25
J 0
(2000 1200);
DISPLAY 0.872340 (2000 1200);
PAINT AQUA (2000 1200);
DISPLAY INVISIBLE (2000 1200);
FORCEPROP 2 LAST ROOM SB_DECOUPLING
J 0
(1950 1275);
DISPLAY 1.361702 (1950 1275);
PAINT ORANGE (1950 1275);
DISPLAY INVISIBLE (1950 1275);
FORCEPROP 1 LAST BODY_TYPE PLUMBING
J 0
(1880 1157);
DISPLAY 0.340426 (1880 1157);
PAINT GREEN (1880 1157);
DISPLAY INVISIBLE (1880 1157);
FORCEPROP 1 LAST HDL_POWER GND
J 0
(1925 1350);
DISPLAY 1.170213 (1925 1350);
PAINT GREEN (1925 1350);
DISPLAY INVISIBLE (1925 1350);
FORCEADD CAP_A..1
(-325 4050);
FORCEPROP 1 LAST LOCATION C2N9
J 0
(-275 4150);
DISPLAY 0.617021 (-275 4150);
PAINT AQUA (-275 4150);
FORCEPROP 1 LAST PART_NUMBER D97712-004
J 0
(-275 3900);
DISPLAY 0.617021 (-275 3900);
PAINT BLUE (-275 3900);
FORCEPROP 1 LAST VALUE 1.0UF
J 0
(-275 4100);
DISPLAY 0.617021 (-275 4100);
PAINT SKYBLUE (-275 4100);
FORCEPROP 1 LAST TOLERANCE 10%
J 0
(-275 4000);
DISPLAY 0.617021 (-275 4000);
PAINT SKYBLUE (-275 4000);
FORCEPROP 1 LAST PACK_TYPE 0402V
J 0
(-275 3850);
DISPLAY 0.617021 (-275 3850);
PAINT SKYBLUE (-275 3850);
FORCEPROP 1 LAST VOLTAGE 6.3V
J 0
(-275 4050);
DISPLAY 0.617021 (-275 4050);
PAINT SKYBLUE (-275 4050);
FORCEPROP 1 LAST MATERIAL X6S
J 0
(-275 3950);
DISPLAY 0.617021 (-275 3950);
PAINT SKYBLUE (-275 3950);
FORCEPROP 1 LASTPIN (-325 4150) $PN 1
J 0
(-315 4130);
DISPLAY 0.617021 (-315 4130);
PAINT WHITE (-315 4130);
FORCEPROP 1 LASTPIN (-325 3950) $PN 2
J 0
(-315 3930);
DISPLAY 0.617021 (-315 3930);
PAINT WHITE (-315 3930);
FORCEPROP 2 LAST CDS_LOCATION C2N9
J 0
(-275 4150);
DISPLAY 0.617021 (-275 4150);
PAINT AQUA (-275 4150);
DISPLAY INVISIBLE (-275 4150);
FORCEPROP 2 LAST CDS_LIB dev_discrete
J 0
(-325 4050);
PAINT ORANGE (-325 4050);
DISPLAY INVISIBLE (-325 4050);
FORCEPROP 2 LAST CDS_SEC 1
J 0
(-275 4250);
PAINT MONO (-275 4250);
DISPLAY INVISIBLE (-275 4250);
FORCEPROP 2 LAST $SEC 1
J 0
(-275 4250);
DISPLAY 0.914894 (-275 4250);
PAINT MONO (-275 4250);
DISPLAY INVISIBLE (-275 4250);
FORCEPROP 1 LAST PATH I26
J 0
(-275 4200);
DISPLAY 0.978723 (-275 4200);
PAINT WHITE (-275 4200);
DISPLAY INVISIBLE (-275 4200);
FORCEPROP 2 LAST ROOM SB_DECOUPLING
J 0
(-275 4200);
DISPLAY 1.361702 (-275 4200);
PAINT ORANGE (-275 4200);
DISPLAY INVISIBLE (-275 4200);
FORCEADD CAP_A..1
(-725 4050);
FORCEPROP 1 LAST LOCATION C2N3
J 0
(-675 4150);
DISPLAY 0.617021 (-675 4150);
PAINT AQUA (-675 4150);
FORCEPROP 1 LAST PART_NUMBER D97712-004
J 0
(-675 3900);
DISPLAY 0.617021 (-675 3900);
PAINT BLUE (-675 3900);
FORCEPROP 1 LAST VALUE 1.0UF
J 0
(-675 4100);
DISPLAY 0.617021 (-675 4100);
PAINT SKYBLUE (-675 4100);
FORCEPROP 1 LAST TOLERANCE 10%
J 0
(-675 4000);
DISPLAY 0.617021 (-675 4000);
PAINT SKYBLUE (-675 4000);
FORCEPROP 1 LAST PACK_TYPE 0402V
J 0
(-675 3850);
DISPLAY 0.617021 (-675 3850);
PAINT SKYBLUE (-675 3850);
FORCEPROP 1 LAST VOLTAGE 6.3V
J 0
(-675 4050);
DISPLAY 0.617021 (-675 4050);
PAINT SKYBLUE (-675 4050);
FORCEPROP 1 LAST MATERIAL X6S
J 0
(-675 3950);
DISPLAY 0.617021 (-675 3950);
PAINT SKYBLUE (-675 3950);
FORCEPROP 1 LASTPIN (-725 4150) $PN 1
J 0
(-715 4130);
DISPLAY 0.617021 (-715 4130);
PAINT WHITE (-715 4130);
FORCEPROP 1 LASTPIN (-725 3950) $PN 2
J 0
(-715 3930);
DISPLAY 0.617021 (-715 3930);
PAINT WHITE (-715 3930);
FORCEPROP 2 LAST CDS_LOCATION C2N3
J 0
(-675 4150);
DISPLAY 0.617021 (-675 4150);
PAINT AQUA (-675 4150);
DISPLAY INVISIBLE (-675 4150);
FORCEPROP 2 LAST BOM_COST SB
J 0
(-675 3800);
PAINT MONO (-675 3800);
DISPLAY INVISIBLE (-675 3800);
FORCEPROP 2 LAST CDS_LIB dev_discrete
J 0
(-725 4050);
PAINT ORANGE (-725 4050);
DISPLAY INVISIBLE (-725 4050);
FORCEPROP 2 LAST CDS_SEC 1
J 0
(-675 4250);
DISPLAY 1.361702 (-675 4250);
PAINT ORANGE (-675 4250);
DISPLAY INVISIBLE (-675 4250);
FORCEPROP 2 LAST $SEC 1
J 0
(-675 4250);
DISPLAY 0.914894 (-675 4250);
PAINT MONO (-675 4250);
DISPLAY INVISIBLE (-675 4250);
FORCEPROP 1 LAST PATH I27
J 0
(-675 4200);
DISPLAY 0.978723 (-675 4200);
PAINT WHITE (-675 4200);
DISPLAY INVISIBLE (-675 4200);
FORCEPROP 2 LAST ROOM SB_DECOUPLING
J 0
(-725 4050);
PAINT WHITE (-725 4050);
DISPLAY INVISIBLE (-725 4050);
FORCEADD CAP_A..1
(-300 3025);
FORCEPROP 1 LAST LOCATION C2N4
J 0
(-250 3125);
DISPLAY 0.617021 (-250 3125);
PAINT AQUA (-250 3125);
FORCEPROP 1 LAST PART_NUMBER D97712-004
J 0
(-250 2875);
DISPLAY 0.617021 (-250 2875);
PAINT BLUE (-250 2875);
FORCEPROP 1 LAST VALUE 1.0UF
J 0
(-250 3075);
DISPLAY 0.617021 (-250 3075);
PAINT SKYBLUE (-250 3075);
FORCEPROP 1 LAST TOLERANCE 10%
J 0
(-250 2975);
DISPLAY 0.617021 (-250 2975);
PAINT SKYBLUE (-250 2975);
FORCEPROP 1 LAST PACK_TYPE 0402V
J 0
(-250 2825);
DISPLAY 0.617021 (-250 2825);
PAINT SKYBLUE (-250 2825);
FORCEPROP 1 LAST VOLTAGE 6.3V
J 0
(-250 3025);
DISPLAY 0.617021 (-250 3025);
PAINT SKYBLUE (-250 3025);
FORCEPROP 1 LAST MATERIAL X6S
J 0
(-250 2925);
DISPLAY 0.617021 (-250 2925);
PAINT SKYBLUE (-250 2925);
FORCEPROP 1 LASTPIN (-300 3125) $PN 1
J 0
(-290 3105);
DISPLAY 0.617021 (-290 3105);
PAINT WHITE (-290 3105);
FORCEPROP 1 LASTPIN (-300 2925) $PN 2
J 0
(-290 2905);
DISPLAY 0.617021 (-290 2905);
PAINT WHITE (-290 2905);
FORCEPROP 2 LAST CDS_LOCATION C2N4
J 0
(-250 3125);
DISPLAY 0.617021 (-250 3125);
PAINT AQUA (-250 3125);
DISPLAY INVISIBLE (-250 3125);
FORCEPROP 2 LAST CDS_LIB dev_discrete
J 0
(-300 3025);
PAINT ORANGE (-300 3025);
DISPLAY INVISIBLE (-300 3025);
FORCEPROP 2 LAST CDS_SEC 1
J 0
(-250 3225);
PAINT MONO (-250 3225);
DISPLAY INVISIBLE (-250 3225);
FORCEPROP 2 LAST $SEC 1
J 0
(-250 3225);
DISPLAY 0.914894 (-250 3225);
PAINT MONO (-250 3225);
DISPLAY INVISIBLE (-250 3225);
FORCEPROP 1 LAST PATH I28
J 0
(-250 3175);
DISPLAY 0.978723 (-250 3175);
PAINT WHITE (-250 3175);
DISPLAY INVISIBLE (-250 3175);
FORCEPROP 2 LAST ROOM SB_DECOUPLING
J 0
(-250 3175);
DISPLAY 1.361702 (-250 3175);
PAINT ORANGE (-250 3175);
DISPLAY INVISIBLE (-250 3175);
FORCEADD CAP_A..1
(-700 3025);
FORCEPROP 1 LAST LOCATION C2N12
J 0
(-650 3125);
DISPLAY 0.617021 (-650 3125);
PAINT AQUA (-650 3125);
FORCEPROP 1 LAST PART_NUMBER D97712-004
J 0
(-650 2875);
DISPLAY 0.617021 (-650 2875);
PAINT BLUE (-650 2875);
FORCEPROP 1 LAST VALUE 1.0UF
J 0
(-650 3075);
DISPLAY 0.617021 (-650 3075);
PAINT SKYBLUE (-650 3075);
FORCEPROP 1 LAST TOLERANCE 10%
J 0
(-650 2975);
DISPLAY 0.617021 (-650 2975);
PAINT SKYBLUE (-650 2975);
FORCEPROP 1 LAST PACK_TYPE 0402V
J 0
(-650 2825);
DISPLAY 0.617021 (-650 2825);
PAINT SKYBLUE (-650 2825);
FORCEPROP 1 LAST VOLTAGE 6.3V
J 0
(-650 3025);
DISPLAY 0.617021 (-650 3025);
PAINT SKYBLUE (-650 3025);
FORCEPROP 1 LAST MATERIAL X6S
J 0
(-650 2925);
DISPLAY 0.617021 (-650 2925);
PAINT SKYBLUE (-650 2925);
FORCEPROP 1 LASTPIN (-700 3125) $PN 1
J 0
(-690 3105);
DISPLAY 0.617021 (-690 3105);
PAINT WHITE (-690 3105);
FORCEPROP 1 LASTPIN (-700 2925) $PN 2
J 0
(-690 2905);
DISPLAY 0.617021 (-690 2905);
PAINT WHITE (-690 2905);
FORCEPROP 2 LAST CDS_LOCATION C2N12
J 0
(-650 3125);
DISPLAY 0.617021 (-650 3125);
PAINT AQUA (-650 3125);
DISPLAY INVISIBLE (-650 3125);
FORCEPROP 2 LAST BOM_COST SB
J 0
(-650 2775);
PAINT MONO (-650 2775);
DISPLAY INVISIBLE (-650 2775);
FORCEPROP 2 LAST CDS_LIB dev_discrete
J 0
(-700 3025);
PAINT ORANGE (-700 3025);
DISPLAY INVISIBLE (-700 3025);
FORCEPROP 2 LAST CDS_SEC 1
J 0
(-650 3225);
DISPLAY 1.361702 (-650 3225);
PAINT ORANGE (-650 3225);
DISPLAY INVISIBLE (-650 3225);
FORCEPROP 2 LAST $SEC 1
J 0
(-650 3225);
DISPLAY 0.914894 (-650 3225);
PAINT MONO (-650 3225);
DISPLAY INVISIBLE (-650 3225);
FORCEPROP 1 LAST PATH I29
J 0
(-650 3175);
DISPLAY 0.978723 (-650 3175);
PAINT WHITE (-650 3175);
DISPLAY INVISIBLE (-650 3175);
FORCEPROP 2 LAST ROOM SB_DECOUPLING
J 0
(-700 3025);
PAINT WHITE (-700 3025);
DISPLAY INVISIBLE (-700 3025);
FORCEADD CAP_A..1
(1825 4475);
FORCEPROP 1 LAST LOCATION C3L26
J 0
(1875 4575);
DISPLAY 0.617021 (1875 4575);
PAINT AQUA (1875 4575);
FORCEPROP 1 LAST PART_NUMBER E15431-004
J 0
(1875 4325);
DISPLAY 0.617021 (1875 4325);
PAINT BLUE (1875 4325);
FORCEPROP 1 LAST VALUE 22.0UF
J 0
(1875 4525);
DISPLAY 0.617021 (1875 4525);
PAINT SKYBLUE (1875 4525);
FORCEPROP 1 LAST TOLERANCE 20%
J 0
(1875 4425);
DISPLAY 0.617021 (1875 4425);
PAINT SKYBLUE (1875 4425);
FORCEPROP 1 LAST PACK_TYPE 0603V
J 0
(1875 4275);
DISPLAY 0.617021 (1875 4275);
PAINT SKYBLUE (1875 4275);
FORCEPROP 1 LAST VOLTAGE 4V
J 0
(1875 4475);
DISPLAY 0.617021 (1875 4475);
PAINT SKYBLUE (1875 4475);
FORCEPROP 1 LAST MATERIAL X6S
J 0
(1875 4375);
DISPLAY 0.617021 (1875 4375);
PAINT SKYBLUE (1875 4375);
FORCEPROP 1 LASTPIN (1825 4575) $PN 1
J 0
(1835 4555);
DISPLAY 0.617021 (1835 4555);
PAINT WHITE (1835 4555);
FORCEPROP 1 LASTPIN (1825 4375) $PN 2
J 0
(1835 4355);
DISPLAY 0.617021 (1835 4355);
PAINT WHITE (1835 4355);
FORCEPROP 2 LAST CDS_LOCATION C3L26
J 0
(1875 4575);
DISPLAY 0.617021 (1875 4575);
PAINT AQUA (1875 4575);
DISPLAY INVISIBLE (1875 4575);
FORCEPROP 2 LAST BOM_COST SB
J 0
(1875 4675);
DISPLAY 1.361702 (1875 4675);
PAINT ORANGE (1875 4675);
DISPLAY INVISIBLE (1875 4675);
FORCEPROP 2 LAST CDS_LIB dev_discrete
J 0
(1825 4475);
PAINT ORANGE (1825 4475);
DISPLAY INVISIBLE (1825 4475);
FORCEPROP 2 LAST CDS_SEC 1
J 0
(1875 4675);
DISPLAY 1.361702 (1875 4675);
PAINT ORANGE (1875 4675);
DISPLAY INVISIBLE (1875 4675);
FORCEPROP 2 LAST $SEC 1
J 0
(1875 4675);
DISPLAY 0.914894 (1875 4675);
PAINT MONO (1875 4675);
DISPLAY INVISIBLE (1875 4675);
FORCEPROP 1 LAST PATH I3
J 0
(1875 4625);
DISPLAY 0.978723 (1875 4625);
PAINT WHITE (1875 4625);
DISPLAY INVISIBLE (1875 4625);
FORCEPROP 2 LAST ROOM SB_DECOUPLING
J 0
(1875 4625);
DISPLAY 1.361702 (1875 4625);
PAINT ORANGE (1875 4625);
DISPLAY INVISIBLE (1875 4625);
FORCEADD CAP_A..1
(-1100 4050);
FORCEPROP 1 LAST LOCATION C2N11
J 0
(-1050 4150);
DISPLAY 0.617021 (-1050 4150);
PAINT AQUA (-1050 4150);
FORCEPROP 1 LAST PART_NUMBER D97712-004
J 0
(-1050 3900);
DISPLAY 0.617021 (-1050 3900);
PAINT BLUE (-1050 3900);
FORCEPROP 1 LAST VALUE 1.0UF
J 0
(-1050 4100);
DISPLAY 0.617021 (-1050 4100);
PAINT SKYBLUE (-1050 4100);
FORCEPROP 1 LAST TOLERANCE 10%
J 0
(-1050 4000);
DISPLAY 0.617021 (-1050 4000);
PAINT SKYBLUE (-1050 4000);
FORCEPROP 1 LAST VOLTAGE 6.3V
J 0
(-1050 4050);
DISPLAY 0.617021 (-1050 4050);
PAINT SKYBLUE (-1050 4050);
FORCEPROP 1 LAST MATERIAL X6S
J 0
(-1050 3950);
DISPLAY 0.617021 (-1050 3950);
PAINT SKYBLUE (-1050 3950);
FORCEPROP 1 LASTPIN (-1100 4150) $PN 1
J 0
(-1090 4130);
DISPLAY 0.617021 (-1090 4130);
PAINT WHITE (-1090 4130);
FORCEPROP 1 LASTPIN (-1100 3950) $PN 2
J 0
(-1090 3930);
DISPLAY 0.617021 (-1090 3930);
PAINT WHITE (-1090 3930);
FORCEPROP 1 LAST PACK_TYPE 0402V
J 0
(-1050 3850);
DISPLAY 0.617021 (-1050 3850);
PAINT SKYBLUE (-1050 3850);
FORCEPROP 2 LAST CDS_LOCATION C2N11
J 0
(-1050 4150);
DISPLAY 0.617021 (-1050 4150);
PAINT AQUA (-1050 4150);
DISPLAY INVISIBLE (-1050 4150);
FORCEPROP 2 LAST BOM_COST SB
J 0
(-1050 3800);
PAINT MONO (-1050 3800);
DISPLAY INVISIBLE (-1050 3800);
FORCEPROP 2 LAST CDS_LIB dev_discrete
J 0
(-1100 4050);
PAINT ORANGE (-1100 4050);
DISPLAY INVISIBLE (-1100 4050);
FORCEPROP 2 LAST CDS_SEC 1
J 0
(-1050 4250);
PAINT MONO (-1050 4250);
DISPLAY INVISIBLE (-1050 4250);
FORCEPROP 2 LAST $SEC 1
J 0
(-1050 4250);
DISPLAY 0.914894 (-1050 4250);
PAINT MONO (-1050 4250);
DISPLAY INVISIBLE (-1050 4250);
FORCEPROP 1 LAST PATH I30
J 0
(-1050 4200);
DISPLAY 0.978723 (-1050 4200);
PAINT WHITE (-1050 4200);
DISPLAY INVISIBLE (-1050 4200);
FORCEPROP 2 LAST ROOM SB_DECOUPLING
J 0
(-1100 4050);
PAINT WHITE (-1100 4050);
DISPLAY INVISIBLE (-1100 4050);
FORCEADD CAP_A..1
(-1475 4050);
FORCEPROP 1 LAST PART_NUMBER D97712-004
J 0
(-1425 3900);
DISPLAY 0.617021 (-1425 3900);
PAINT BLUE (-1425 3900);
FORCEPROP 1 LAST VALUE 1.0UF
J 0
(-1425 4100);
DISPLAY 0.617021 (-1425 4100);
PAINT SKYBLUE (-1425 4100);
FORCEPROP 1 LAST TOLERANCE 10%
J 0
(-1425 4000);
DISPLAY 0.617021 (-1425 4000);
PAINT SKYBLUE (-1425 4000);
FORCEPROP 1 LAST PACK_TYPE 0402V
J 0
(-1425 3850);
DISPLAY 0.617021 (-1425 3850);
PAINT SKYBLUE (-1425 3850);
FORCEPROP 1 LAST VOLTAGE 6.3V
J 0
(-1425 4050);
DISPLAY 0.617021 (-1425 4050);
PAINT SKYBLUE (-1425 4050);
FORCEPROP 1 LAST MATERIAL X6S
J 0
(-1425 3950);
DISPLAY 0.617021 (-1425 3950);
PAINT SKYBLUE (-1425 3950);
FORCEPROP 1 LASTPIN (-1475 4150) $PN 1
J 0
(-1465 4130);
DISPLAY 0.617021 (-1465 4130);
PAINT WHITE (-1465 4130);
FORCEPROP 1 LASTPIN (-1475 3950) $PN 2
J 0
(-1465 3930);
DISPLAY 0.617021 (-1465 3930);
PAINT WHITE (-1465 3930);
FORCEPROP 1 LAST LOCATION C3N19
J 0
(-1425 4150);
DISPLAY 0.617021 (-1425 4150);
PAINT AQUA (-1425 4150);
FORCEPROP 2 LAST CDS_LOCATION C3N19
J 0
(-1425 4150);
DISPLAY 0.617021 (-1425 4150);
PAINT AQUA (-1425 4150);
DISPLAY INVISIBLE (-1425 4150);
FORCEPROP 2 LAST BOM_COST SB
J 0
(-1425 3800);
PAINT MONO (-1425 3800);
DISPLAY INVISIBLE (-1425 3800);
FORCEPROP 2 LAST CDS_LIB dev_discrete
J 0
(-1475 4050);
PAINT ORANGE (-1475 4050);
DISPLAY INVISIBLE (-1475 4050);
FORCEPROP 2 LAST CDS_SEC 1
J 0
(-1425 4250);
DISPLAY 1.361702 (-1425 4250);
PAINT ORANGE (-1425 4250);
DISPLAY INVISIBLE (-1425 4250);
FORCEPROP 2 LAST $SEC 1
J 0
(-1425 4250);
DISPLAY 0.914894 (-1425 4250);
PAINT MONO (-1425 4250);
DISPLAY INVISIBLE (-1425 4250);
FORCEPROP 1 LAST PATH I31
J 0
(-1425 4200);
DISPLAY 0.978723 (-1425 4200);
PAINT WHITE (-1425 4200);
DISPLAY INVISIBLE (-1425 4200);
FORCEPROP 2 LAST ROOM SB_DECOUPLING
J 0
(-1475 4050);
PAINT WHITE (-1475 4050);
DISPLAY INVISIBLE (-1475 4050);
FORCEADD CAP_A..1
(-1850 4050);
FORCEPROP 1 LAST LOCATION C3N3
J 0
(-1800 4150);
DISPLAY 0.617021 (-1800 4150);
PAINT AQUA (-1800 4150);
FORCEPROP 1 LAST PART_NUMBER D97712-004
J 0
(-1800 3900);
DISPLAY 0.617021 (-1800 3900);
PAINT BLUE (-1800 3900);
FORCEPROP 1 LAST VALUE 1.0UF
J 0
(-1800 4100);
DISPLAY 0.617021 (-1800 4100);
PAINT SKYBLUE (-1800 4100);
FORCEPROP 1 LAST TOLERANCE 10%
J 0
(-1800 4000);
DISPLAY 0.617021 (-1800 4000);
PAINT SKYBLUE (-1800 4000);
FORCEPROP 1 LAST PACK_TYPE 0402V
J 0
(-1800 3850);
DISPLAY 0.617021 (-1800 3850);
PAINT SKYBLUE (-1800 3850);
FORCEPROP 1 LAST VOLTAGE 6.3V
J 0
(-1800 4050);
DISPLAY 0.617021 (-1800 4050);
PAINT SKYBLUE (-1800 4050);
FORCEPROP 1 LAST MATERIAL X6S
J 0
(-1800 3950);
DISPLAY 0.617021 (-1800 3950);
PAINT SKYBLUE (-1800 3950);
FORCEPROP 1 LASTPIN (-1850 4150) $PN 1
J 0
(-1840 4130);
DISPLAY 0.617021 (-1840 4130);
PAINT WHITE (-1840 4130);
FORCEPROP 1 LASTPIN (-1850 3950) $PN 2
J 0
(-1840 3930);
DISPLAY 0.617021 (-1840 3930);
PAINT WHITE (-1840 3930);
FORCEPROP 2 LAST CDS_LOCATION C3N3
J 0
(-1800 4150);
DISPLAY 0.617021 (-1800 4150);
PAINT AQUA (-1800 4150);
DISPLAY INVISIBLE (-1800 4150);
FORCEPROP 2 LAST BOM_COST SB
J 0
(-1800 3800);
PAINT MONO (-1800 3800);
DISPLAY INVISIBLE (-1800 3800);
FORCEPROP 2 LAST CDS_LIB dev_discrete
J 0
(-1850 4050);
PAINT ORANGE (-1850 4050);
DISPLAY INVISIBLE (-1850 4050);
FORCEPROP 2 LAST CDS_SEC 1
J 0
(-1800 4250);
DISPLAY 1.361702 (-1800 4250);
PAINT ORANGE (-1800 4250);
DISPLAY INVISIBLE (-1800 4250);
FORCEPROP 2 LAST $SEC 1
J 0
(-1800 4250);
DISPLAY 0.914894 (-1800 4250);
PAINT MONO (-1800 4250);
DISPLAY INVISIBLE (-1800 4250);
FORCEPROP 1 LAST PATH I32
J 0
(-1800 4200);
DISPLAY 0.978723 (-1800 4200);
PAINT WHITE (-1800 4200);
DISPLAY INVISIBLE (-1800 4200);
FORCEPROP 2 LAST ROOM SB_DECOUPLING
J 0
(-1850 4050);
PAINT WHITE (-1850 4050);
DISPLAY INVISIBLE (-1850 4050);
FORCEADD GND..1
(-1750 3750);
FORCEPROP 3 LASTPIN (-1750 3800) SIG_NAME GND\g
J 0
(-1740 3810);
DISPLAY 0.659574 (-1740 3810);
PAINT MONO (-1740 3810);
DISPLAY INVISIBLE (-1740 3810);
FORCEPROP 1 LAST VOLTAGE 0
J 0
(-1750 3750);
PAINT SKYBLUE (-1750 3750);
DISPLAY INVISIBLE (-1750 3750);
FORCEPROP 1 LAST SIZE 1B
J 0
(-1675 3700);
DISPLAY 1.404255 (-1675 3700);
PAINT GREEN (-1675 3700);
DISPLAY INVISIBLE (-1675 3700);
FORCEPROP 2 LAST CDS_LIB mstr_symbols
J 0
(-1750 3750);
PAINT ORANGE (-1750 3750);
DISPLAY INVISIBLE (-1750 3750);
FORCEPROP 2 LAST BOM_COST SB
J 0
(-1800 3825);
PAINT MONO (-1800 3825);
DISPLAY INVISIBLE (-1800 3825);
FORCEPROP 1 LAST PATH I33
J 0
(-1675 3750);
DISPLAY 0.872340 (-1675 3750);
PAINT AQUA (-1675 3750);
DISPLAY INVISIBLE (-1675 3750);
FORCEPROP 2 LAST ROOM SB_DECOUPLING
J 0
(-2225 3825);
PAINT WHITE (-2225 3825);
DISPLAY INVISIBLE (-2225 3825);
FORCEPROP 1 LAST BODY_TYPE PLUMBING
J 0
(-1795 3707);
DISPLAY 0.340426 (-1795 3707);
PAINT GREEN (-1795 3707);
DISPLAY INVISIBLE (-1795 3707);
FORCEPROP 1 LAST HDL_POWER GND
J 0
(-1750 3900);
DISPLAY 1.404255 (-1750 3900);
PAINT GREEN (-1750 3900);
DISPLAY INVISIBLE (-1750 3900);
FORCEADD CAP_A..1
(-1075 3025);
FORCEPROP 1 LAST PART_NUMBER D97712-004
J 0
(-1025 2875);
DISPLAY 0.617021 (-1025 2875);
PAINT BLUE (-1025 2875);
FORCEPROP 1 LAST TOLERANCE 10%
J 0
(-1025 2975);
DISPLAY 0.617021 (-1025 2975);
PAINT SKYBLUE (-1025 2975);
FORCEPROP 1 LAST PACK_TYPE 0402V
J 0
(-1025 2825);
DISPLAY 0.617021 (-1025 2825);
PAINT SKYBLUE (-1025 2825);
FORCEPROP 1 LAST VOLTAGE 6.3V
J 0
(-1025 3025);
DISPLAY 0.617021 (-1025 3025);
PAINT SKYBLUE (-1025 3025);
FORCEPROP 1 LAST MATERIAL X6S
J 0
(-1025 2925);
DISPLAY 0.617021 (-1025 2925);
PAINT SKYBLUE (-1025 2925);
FORCEPROP 1 LASTPIN (-1075 3125) $PN 1
J 0
(-1065 3105);
DISPLAY 0.617021 (-1065 3105);
PAINT WHITE (-1065 3105);
FORCEPROP 1 LASTPIN (-1075 2925) $PN 2
J 0
(-1065 2905);
DISPLAY 0.617021 (-1065 2905);
PAINT WHITE (-1065 2905);
FORCEPROP 1 LAST LOCATION C3N1
J 0
(-1025 3125);
DISPLAY 0.617021 (-1025 3125);
PAINT AQUA (-1025 3125);
FORCEPROP 1 LAST VALUE 1.0UF
J 0
(-1025 3075);
DISPLAY 0.617021 (-1025 3075);
PAINT SKYBLUE (-1025 3075);
FORCEPROP 2 LAST CDS_LOCATION C3N1
J 0
(-1025 3125);
DISPLAY 0.617021 (-1025 3125);
PAINT AQUA (-1025 3125);
DISPLAY INVISIBLE (-1025 3125);
FORCEPROP 2 LAST BOM_COST SB
J 0
(-1025 2775);
PAINT MONO (-1025 2775);
DISPLAY INVISIBLE (-1025 2775);
FORCEPROP 2 LAST CDS_LIB dev_discrete
J 0
(-1075 3025);
PAINT ORANGE (-1075 3025);
DISPLAY INVISIBLE (-1075 3025);
FORCEPROP 2 LAST CDS_SEC 1
J 0
(-1025 3225);
PAINT MONO (-1025 3225);
DISPLAY INVISIBLE (-1025 3225);
FORCEPROP 2 LAST $SEC 1
J 0
(-1025 3225);
DISPLAY 0.914894 (-1025 3225);
PAINT MONO (-1025 3225);
DISPLAY INVISIBLE (-1025 3225);
FORCEPROP 1 LAST PATH I34
J 0
(-1025 3175);
DISPLAY 0.978723 (-1025 3175);
PAINT WHITE (-1025 3175);
DISPLAY INVISIBLE (-1025 3175);
FORCEPROP 2 LAST ROOM SB_DECOUPLING
J 0
(-1075 3025);
PAINT WHITE (-1075 3025);
DISPLAY INVISIBLE (-1075 3025);
FORCEADD CAP_A..1
(-1450 3025);
FORCEPROP 1 LAST LOCATION C3N7
J 0
(-1400 3125);
DISPLAY 0.617021 (-1400 3125);
PAINT AQUA (-1400 3125);
FORCEPROP 1 LAST PART_NUMBER D97712-004
J 0
(-1400 2875);
DISPLAY 0.617021 (-1400 2875);
PAINT BLUE (-1400 2875);
FORCEPROP 1 LAST VALUE 1.0UF
J 0
(-1400 3075);
DISPLAY 0.617021 (-1400 3075);
PAINT SKYBLUE (-1400 3075);
FORCEPROP 1 LAST TOLERANCE 10%
J 0
(-1400 2975);
DISPLAY 0.617021 (-1400 2975);
PAINT SKYBLUE (-1400 2975);
FORCEPROP 1 LAST PACK_TYPE 0402V
J 0
(-1400 2825);
DISPLAY 0.617021 (-1400 2825);
PAINT SKYBLUE (-1400 2825);
FORCEPROP 1 LAST VOLTAGE 6.3V
J 0
(-1400 3025);
DISPLAY 0.617021 (-1400 3025);
PAINT SKYBLUE (-1400 3025);
FORCEPROP 1 LAST MATERIAL X6S
J 0
(-1400 2925);
DISPLAY 0.617021 (-1400 2925);
PAINT SKYBLUE (-1400 2925);
FORCEPROP 1 LASTPIN (-1450 3125) $PN 1
J 0
(-1440 3105);
DISPLAY 0.617021 (-1440 3105);
PAINT WHITE (-1440 3105);
FORCEPROP 1 LASTPIN (-1450 2925) $PN 2
J 0
(-1440 2905);
DISPLAY 0.617021 (-1440 2905);
PAINT WHITE (-1440 2905);
FORCEPROP 2 LAST CDS_LOCATION C3N7
J 0
(-1400 3125);
DISPLAY 0.617021 (-1400 3125);
PAINT AQUA (-1400 3125);
DISPLAY INVISIBLE (-1400 3125);
FORCEPROP 2 LAST BOM_COST SB
J 0
(-1400 2775);
PAINT MONO (-1400 2775);
DISPLAY INVISIBLE (-1400 2775);
FORCEPROP 2 LAST CDS_LIB dev_discrete
J 0
(-1450 3025);
PAINT ORANGE (-1450 3025);
DISPLAY INVISIBLE (-1450 3025);
FORCEPROP 2 LAST CDS_SEC 1
J 0
(-1400 3225);
DISPLAY 1.361702 (-1400 3225);
PAINT ORANGE (-1400 3225);
DISPLAY INVISIBLE (-1400 3225);
FORCEPROP 2 LAST $SEC 1
J 0
(-1400 3225);
DISPLAY 0.914894 (-1400 3225);
PAINT MONO (-1400 3225);
DISPLAY INVISIBLE (-1400 3225);
FORCEPROP 1 LAST PATH I35
J 0
(-1400 3175);
DISPLAY 0.978723 (-1400 3175);
PAINT WHITE (-1400 3175);
DISPLAY INVISIBLE (-1400 3175);
FORCEPROP 2 LAST ROOM SB_DECOUPLING
J 0
(-1450 3025);
PAINT WHITE (-1450 3025);
DISPLAY INVISIBLE (-1450 3025);
FORCEADD CAP_A..1
(-1825 3025);
FORCEPROP 1 LAST LOCATION C3N16
J 0
(-1775 3125);
DISPLAY 0.617021 (-1775 3125);
PAINT AQUA (-1775 3125);
FORCEPROP 1 LAST PART_NUMBER D97712-004
J 0
(-1775 2875);
DISPLAY 0.617021 (-1775 2875);
PAINT BLUE (-1775 2875);
FORCEPROP 1 LAST VALUE 1.0UF
J 0
(-1775 3075);
DISPLAY 0.617021 (-1775 3075);
PAINT SKYBLUE (-1775 3075);
FORCEPROP 1 LAST TOLERANCE 10%
J 0
(-1775 2975);
DISPLAY 0.617021 (-1775 2975);
PAINT SKYBLUE (-1775 2975);
FORCEPROP 1 LAST PACK_TYPE 0402V
J 0
(-1775 2825);
DISPLAY 0.617021 (-1775 2825);
PAINT SKYBLUE (-1775 2825);
FORCEPROP 1 LAST VOLTAGE 6.3V
J 0
(-1775 3025);
DISPLAY 0.617021 (-1775 3025);
PAINT SKYBLUE (-1775 3025);
FORCEPROP 1 LAST MATERIAL X6S
J 0
(-1775 2925);
DISPLAY 0.617021 (-1775 2925);
PAINT SKYBLUE (-1775 2925);
FORCEPROP 1 LASTPIN (-1825 3125) $PN 1
J 0
(-1815 3105);
DISPLAY 0.617021 (-1815 3105);
PAINT WHITE (-1815 3105);
FORCEPROP 1 LASTPIN (-1825 2925) $PN 2
J 0
(-1815 2905);
DISPLAY 0.617021 (-1815 2905);
PAINT WHITE (-1815 2905);
FORCEPROP 2 LAST CDS_LOCATION C3N16
J 0
(-1775 3125);
DISPLAY 0.617021 (-1775 3125);
PAINT AQUA (-1775 3125);
DISPLAY INVISIBLE (-1775 3125);
FORCEPROP 2 LAST BOM_COST SB
J 0
(-1775 2775);
PAINT MONO (-1775 2775);
DISPLAY INVISIBLE (-1775 2775);
FORCEPROP 2 LAST CDS_LIB dev_discrete
J 0
(-1825 3025);
PAINT ORANGE (-1825 3025);
DISPLAY INVISIBLE (-1825 3025);
FORCEPROP 2 LAST CDS_SEC 1
J 0
(-1775 3225);
DISPLAY 1.361702 (-1775 3225);
PAINT ORANGE (-1775 3225);
DISPLAY INVISIBLE (-1775 3225);
FORCEPROP 2 LAST $SEC 1
J 0
(-1775 3225);
DISPLAY 0.914894 (-1775 3225);
PAINT MONO (-1775 3225);
DISPLAY INVISIBLE (-1775 3225);
FORCEPROP 1 LAST PATH I36
J 0
(-1775 3175);
DISPLAY 0.978723 (-1775 3175);
PAINT WHITE (-1775 3175);
DISPLAY INVISIBLE (-1775 3175);
FORCEPROP 2 LAST ROOM SB_DECOUPLING
J 0
(-1825 3025);
PAINT WHITE (-1825 3025);
DISPLAY INVISIBLE (-1825 3025);
FORCEADD GND..1
(-1725 2725);
FORCEPROP 3 LASTPIN (-1725 2775) SIG_NAME GND\g
J 0
(-1715 2785);
DISPLAY 0.659574 (-1715 2785);
PAINT MONO (-1715 2785);
DISPLAY INVISIBLE (-1715 2785);
FORCEPROP 1 LAST VOLTAGE 0
J 0
(-1725 2725);
PAINT SKYBLUE (-1725 2725);
DISPLAY INVISIBLE (-1725 2725);
FORCEPROP 1 LAST SIZE 1B
J 0
(-1650 2675);
DISPLAY 1.404255 (-1650 2675);
PAINT GREEN (-1650 2675);
DISPLAY INVISIBLE (-1650 2675);
FORCEPROP 2 LAST CDS_LIB mstr_symbols
J 0
(-1725 2725);
PAINT ORANGE (-1725 2725);
DISPLAY INVISIBLE (-1725 2725);
FORCEPROP 2 LAST BOM_COST SB
J 0
(-1775 2800);
PAINT MONO (-1775 2800);
DISPLAY INVISIBLE (-1775 2800);
FORCEPROP 1 LAST PATH I37
J 0
(-1650 2725);
DISPLAY 0.872340 (-1650 2725);
PAINT AQUA (-1650 2725);
DISPLAY INVISIBLE (-1650 2725);
FORCEPROP 2 LAST ROOM SB_DECOUPLING
J 0
(-2200 2800);
PAINT WHITE (-2200 2800);
DISPLAY INVISIBLE (-2200 2800);
FORCEPROP 1 LAST BODY_TYPE PLUMBING
J 0
(-1770 2682);
DISPLAY 0.340426 (-1770 2682);
PAINT GREEN (-1770 2682);
DISPLAY INVISIBLE (-1770 2682);
FORCEPROP 1 LAST HDL_POWER GND
J 0
(-1725 2875);
DISPLAY 1.404255 (-1725 2875);
PAINT GREEN (-1725 2875);
DISPLAY INVISIBLE (-1725 2875);
FORCEADD CAP..1
(-650 1900);
FORCEPROP 1 LAST LOCATION C7A32
J 0
(-600 2000);
DISPLAY 0.617021 (-600 2000);
PAINT AQUA (-600 2000);
FORCEPROP 1 LAST PART_NUMBER C95333-006
J 0
(-600 1750);
DISPLAY 0.617021 (-600 1750);
PAINT BLUE (-600 1750);
FORCEPROP 1 LAST VALUE 47UF
J 0
(-600 1950);
DISPLAY 0.617021 (-600 1950);
PAINT SKYBLUE (-600 1950);
FORCEPROP 1 LAST TOLERANCE 20%
J 0
(-600 1850);
DISPLAY 0.617021 (-600 1850);
PAINT SKYBLUE (-600 1850);
FORCEPROP 1 LAST PACK_TYPE 0805
J 0
(-600 1700);
DISPLAY 0.617021 (-600 1700);
PAINT SKYBLUE (-600 1700);
FORCEPROP 1 LAST VOLTAGE 4V
J 0
(-600 1900);
DISPLAY 0.617021 (-600 1900);
PAINT SKYBLUE (-600 1900);
FORCEPROP 1 LAST MATERIAL X6S
J 0
(-600 1800);
DISPLAY 0.617021 (-600 1800);
PAINT SKYBLUE (-600 1800);
FORCEPROP 1 LASTPIN (-650 1800) $PN 2
J 0
(-640 1780);
DISPLAY 0.617021 (-640 1780);
PAINT WHITE (-640 1780);
FORCEPROP 1 LASTPIN (-650 2000) $PN 1
J 0
(-640 1980);
DISPLAY 0.617021 (-640 1980);
PAINT WHITE (-640 1980);
FORCEPROP 2 LAST CDS_LIB mstr_discrete
J 0
(-650 1900);
PAINT MONO (-650 1900);
DISPLAY INVISIBLE (-650 1900);
FORCEPROP 2 LAST BOM_COST SB
J 0
(-600 2100);
DISPLAY 1.361702 (-600 2100);
PAINT ORANGE (-600 2100);
DISPLAY INVISIBLE (-600 2100);
FORCEPROP 2 LAST CDS_SEC 1
J 0
(-600 2100);
DISPLAY 1.361702 (-600 2100);
PAINT ORANGE (-600 2100);
DISPLAY INVISIBLE (-600 2100);
FORCEPROP 2 LAST $SEC 1
J 0
(-600 2100);
DISPLAY 0.914894 (-600 2100);
PAINT MONO (-600 2100);
DISPLAY INVISIBLE (-600 2100);
FORCEPROP 2 LAST CDS_LOCATION C7A32
J 0
(-600 2000);
DISPLAY 0.617021 (-600 2000);
PAINT AQUA (-600 2000);
DISPLAY INVISIBLE (-600 2000);
FORCEPROP 1 LAST PATH I38
J 0
(-600 2050);
DISPLAY 0.978723 (-600 2050);
PAINT WHITE (-600 2050);
DISPLAY INVISIBLE (-600 2050);
FORCEPROP 2 LAST ROOM SB_DECOUPLING
J 0
(-600 2050);
DISPLAY 1.361702 (-600 2050);
PAINT ORANGE (-600 2050);
DISPLAY INVISIBLE (-600 2050);
FORCEADD PVNN_PCH_STBY..1
(-875 2200);
FORCEPROP 3 LASTPIN (-875 2150) SIG_NAME PVNN_PCH_STBY\g
J 0
(-865 2160);
DISPLAY 0.659574 (-865 2160);
PAINT MONO (-865 2160);
DISPLAY INVISIBLE (-865 2160);
FORCEPROP 1 LAST VOLTAGE 1.0V
J 0
(-920 2157);
DISPLAY 0.340426 (-920 2157);
PAINT SKYBLUE (-920 2157);
DISPLAY INVISIBLE (-920 2157);
FORCEPROP 2 LAST CDS_LIB mstr_symbols
J 0
(-875 2200);
PAINT ORANGE (-875 2200);
DISPLAY INVISIBLE (-875 2200);
FORCEPROP 2 LAST BOM_COST SB
J 0
(-875 2300);
DISPLAY 1.361702 (-875 2300);
PAINT ORANGE (-875 2300);
DISPLAY INVISIBLE (-875 2300);
FORCEPROP 1 LAST PATH I39
J 0
(-825 2225);
DISPLAY 0.872340 (-825 2225);
PAINT AQUA (-825 2225);
DISPLAY INVISIBLE (-825 2225);
FORCEPROP 2 LAST ROOM SB_DECOUPLING
J 0
(-875 2300);
DISPLAY 1.361702 (-875 2300);
PAINT ORANGE (-875 2300);
DISPLAY INVISIBLE (-875 2300);
FORCEPROP 1 LAST BODY_TYPE PLUMBING
J 0
(-920 2157);
DISPLAY 0.340426 (-920 2157);
PAINT GREEN (-920 2157);
DISPLAY INVISIBLE (-920 2157);
FORCEPROP 1 LAST HDL_POWER PVNN_PCH_STBY
J 1
(-875 2250);
DISPLAY 0.872340 (-875 2250);
PAINT GREEN (-875 2250);
DISPLAY INVISIBLE (-875 2250);
FORCEADD CAP_A..1
(1450 4475);
FORCEPROP 1 LAST LOCATION C3L27
J 0
(1500 4575);
DISPLAY 0.617021 (1500 4575);
PAINT AQUA (1500 4575);
FORCEPROP 1 LAST PART_NUMBER E15431-004
J 0
(1500 4325);
DISPLAY 0.617021 (1500 4325);
PAINT BLUE (1500 4325);
FORCEPROP 1 LAST VALUE 22.0UF
J 0
(1500 4525);
DISPLAY 0.617021 (1500 4525);
PAINT SKYBLUE (1500 4525);
FORCEPROP 1 LAST TOLERANCE 20%
J 0
(1500 4425);
DISPLAY 0.617021 (1500 4425);
PAINT SKYBLUE (1500 4425);
FORCEPROP 1 LAST PACK_TYPE 0603V
J 0
(1500 4275);
DISPLAY 0.617021 (1500 4275);
PAINT SKYBLUE (1500 4275);
FORCEPROP 1 LAST VOLTAGE 4V
J 0
(1500 4475);
DISPLAY 0.617021 (1500 4475);
PAINT SKYBLUE (1500 4475);
FORCEPROP 1 LAST MATERIAL X6S
J 0
(1500 4375);
DISPLAY 0.617021 (1500 4375);
PAINT SKYBLUE (1500 4375);
FORCEPROP 1 LASTPIN (1450 4575) $PN 1
J 0
(1460 4555);
DISPLAY 0.617021 (1460 4555);
PAINT WHITE (1460 4555);
FORCEPROP 1 LASTPIN (1450 4375) $PN 2
J 0
(1460 4355);
DISPLAY 0.617021 (1460 4355);
PAINT WHITE (1460 4355);
FORCEPROP 2 LAST CDS_LOCATION C3L27
J 0
(1500 4575);
DISPLAY 0.617021 (1500 4575);
PAINT AQUA (1500 4575);
DISPLAY INVISIBLE (1500 4575);
FORCEPROP 2 LAST BOM_COST SB
J 0
(1500 4675);
DISPLAY 1.361702 (1500 4675);
PAINT ORANGE (1500 4675);
DISPLAY INVISIBLE (1500 4675);
FORCEPROP 2 LAST CDS_LIB dev_discrete
J 0
(1450 4475);
PAINT ORANGE (1450 4475);
DISPLAY INVISIBLE (1450 4475);
FORCEPROP 2 LAST CDS_SEC 1
J 0
(1500 4675);
DISPLAY 1.361702 (1500 4675);
PAINT ORANGE (1500 4675);
DISPLAY INVISIBLE (1500 4675);
FORCEPROP 2 LAST $SEC 1
J 0
(1500 4675);
DISPLAY 0.914894 (1500 4675);
PAINT MONO (1500 4675);
DISPLAY INVISIBLE (1500 4675);
FORCEPROP 1 LAST PATH I4
J 0
(1500 4625);
DISPLAY 0.978723 (1500 4625);
PAINT WHITE (1500 4625);
DISPLAY INVISIBLE (1500 4625);
FORCEPROP 2 LAST ROOM SB_DECOUPLING
J 0
(1500 4625);
DISPLAY 1.361702 (1500 4625);
PAINT ORANGE (1500 4625);
DISPLAY INVISIBLE (1500 4625);
FORCEADD CAP..1
(-1100 1900);
FORCEPROP 1 LAST LOCATION C7A31
J 0
(-1050 2000);
DISPLAY 0.617021 (-1050 2000);
PAINT AQUA (-1050 2000);
FORCEPROP 1 LAST PART_NUMBER C95333-006
J 0
(-1050 1750);
DISPLAY 0.617021 (-1050 1750);
PAINT BLUE (-1050 1750);
FORCEPROP 1 LAST VALUE 47UF
J 0
(-1050 1950);
DISPLAY 0.617021 (-1050 1950);
PAINT SKYBLUE (-1050 1950);
FORCEPROP 1 LAST TOLERANCE 20%
J 0
(-1050 1850);
DISPLAY 0.617021 (-1050 1850);
PAINT SKYBLUE (-1050 1850);
FORCEPROP 1 LAST PACK_TYPE 0805
J 0
(-1050 1700);
DISPLAY 0.617021 (-1050 1700);
PAINT SKYBLUE (-1050 1700);
FORCEPROP 1 LAST VOLTAGE 4V
J 0
(-1050 1900);
DISPLAY 0.617021 (-1050 1900);
PAINT SKYBLUE (-1050 1900);
FORCEPROP 1 LAST MATERIAL X6S
J 0
(-1050 1800);
DISPLAY 0.617021 (-1050 1800);
PAINT SKYBLUE (-1050 1800);
FORCEPROP 1 LASTPIN (-1100 1800) $PN 2
J 0
(-1090 1780);
DISPLAY 0.617021 (-1090 1780);
PAINT WHITE (-1090 1780);
FORCEPROP 1 LASTPIN (-1100 2000) $PN 1
J 0
(-1090 1980);
DISPLAY 0.617021 (-1090 1980);
PAINT WHITE (-1090 1980);
FORCEPROP 2 LAST CDS_LIB mstr_discrete
J 0
(-1100 1900);
PAINT MONO (-1100 1900);
DISPLAY INVISIBLE (-1100 1900);
FORCEPROP 2 LAST BOM_COST SB
J 0
(-1050 2100);
DISPLAY 1.361702 (-1050 2100);
PAINT ORANGE (-1050 2100);
DISPLAY INVISIBLE (-1050 2100);
FORCEPROP 2 LAST CDS_SEC 1
J 0
(-1050 2100);
DISPLAY 1.361702 (-1050 2100);
PAINT ORANGE (-1050 2100);
DISPLAY INVISIBLE (-1050 2100);
FORCEPROP 2 LAST $SEC 1
J 0
(-1050 2100);
DISPLAY 0.914894 (-1050 2100);
PAINT MONO (-1050 2100);
DISPLAY INVISIBLE (-1050 2100);
FORCEPROP 2 LAST CDS_LOCATION C7A31
J 0
(-1050 2000);
DISPLAY 0.617021 (-1050 2000);
PAINT AQUA (-1050 2000);
DISPLAY INVISIBLE (-1050 2000);
FORCEPROP 1 LAST PATH I40
J 0
(-1050 2050);
DISPLAY 0.978723 (-1050 2050);
PAINT WHITE (-1050 2050);
DISPLAY INVISIBLE (-1050 2050);
FORCEPROP 2 LAST ROOM SB_DECOUPLING
J 0
(-1050 2050);
DISPLAY 1.361702 (-1050 2050);
PAINT ORANGE (-1050 2050);
DISPLAY INVISIBLE (-1050 2050);
FORCEADD GND..1
(-875 1525);
FORCEPROP 3 LASTPIN (-875 1575) SIG_NAME GND\g
J 0
(-865 1585);
DISPLAY 0.659574 (-865 1585);
PAINT MONO (-865 1585);
DISPLAY INVISIBLE (-865 1585);
FORCEPROP 1 LAST VOLTAGE 0.0V
J 0
(-920 1482);
DISPLAY 0.340426 (-920 1482);
PAINT SKYBLUE (-920 1482);
DISPLAY INVISIBLE (-920 1482);
FORCEPROP 1 LAST SIZE 1B
J 0
(-800 1475);
DISPLAY 1.170213 (-800 1475);
PAINT AQUA (-800 1475);
DISPLAY INVISIBLE (-800 1475);
FORCEPROP 2 LAST CDS_LIB mstr_symbols
J 0
(-875 1525);
PAINT MONO (-875 1525);
DISPLAY INVISIBLE (-875 1525);
FORCEPROP 2 LAST BOM_COST SB
J 0
(-850 1600);
DISPLAY 1.361702 (-850 1600);
PAINT ORANGE (-850 1600);
DISPLAY INVISIBLE (-850 1600);
FORCEPROP 1 LAST PATH I41
J 0
(-800 1525);
DISPLAY 0.872340 (-800 1525);
PAINT AQUA (-800 1525);
DISPLAY INVISIBLE (-800 1525);
FORCEPROP 2 LAST ROOM SB_DECOUPLING
J 0
(-850 1600);
DISPLAY 1.361702 (-850 1600);
PAINT ORANGE (-850 1600);
DISPLAY INVISIBLE (-850 1600);
FORCEPROP 1 LAST BODY_TYPE PLUMBING
J 0
(-920 1482);
DISPLAY 0.340426 (-920 1482);
PAINT GREEN (-920 1482);
DISPLAY INVISIBLE (-920 1482);
FORCEPROP 1 LAST HDL_POWER GND
J 0
(-875 1675);
DISPLAY 1.170213 (-875 1675);
PAINT GREEN (-875 1675);
DISPLAY INVISIBLE (-875 1675);
FORCEADD CAP_A..1
(-2225 4050);
FORCEPROP 1 LAST LOCATION C3N18
J 0
(-2175 4150);
DISPLAY 0.617021 (-2175 4150);
PAINT AQUA (-2175 4150);
FORCEPROP 1 LAST PART_NUMBER D97712-004
J 0
(-2175 3900);
DISPLAY 0.617021 (-2175 3900);
PAINT BLUE (-2175 3900);
FORCEPROP 1 LAST VALUE 1.0UF
J 0
(-2175 4100);
DISPLAY 0.617021 (-2175 4100);
PAINT SKYBLUE (-2175 4100);
FORCEPROP 1 LAST TOLERANCE 10%
J 0
(-2175 4000);
DISPLAY 0.617021 (-2175 4000);
PAINT SKYBLUE (-2175 4000);
FORCEPROP 1 LAST PACK_TYPE 0402V
J 0
(-2175 3850);
DISPLAY 0.617021 (-2175 3850);
PAINT SKYBLUE (-2175 3850);
FORCEPROP 1 LAST VOLTAGE 6.3V
J 0
(-2175 4050);
DISPLAY 0.617021 (-2175 4050);
PAINT SKYBLUE (-2175 4050);
FORCEPROP 1 LAST MATERIAL X6S
J 0
(-2175 3950);
DISPLAY 0.617021 (-2175 3950);
PAINT SKYBLUE (-2175 3950);
FORCEPROP 1 LASTPIN (-2225 4150) $PN 1
J 0
(-2215 4130);
DISPLAY 0.617021 (-2215 4130);
PAINT WHITE (-2215 4130);
FORCEPROP 1 LASTPIN (-2225 3950) $PN 2
J 0
(-2215 3930);
DISPLAY 0.617021 (-2215 3930);
PAINT WHITE (-2215 3930);
FORCEPROP 2 LAST CDS_LOCATION C3N18
J 0
(-2175 4150);
DISPLAY 0.617021 (-2175 4150);
PAINT AQUA (-2175 4150);
DISPLAY INVISIBLE (-2175 4150);
FORCEPROP 2 LAST BOM_COST SB
J 0
(-2175 3800);
PAINT MONO (-2175 3800);
DISPLAY INVISIBLE (-2175 3800);
FORCEPROP 2 LAST CDS_LIB dev_discrete
J 0
(-2225 4050);
PAINT ORANGE (-2225 4050);
DISPLAY INVISIBLE (-2225 4050);
FORCEPROP 2 LAST CDS_SEC 1
J 0
(-2175 4250);
DISPLAY 1.361702 (-2175 4250);
PAINT ORANGE (-2175 4250);
DISPLAY INVISIBLE (-2175 4250);
FORCEPROP 2 LAST $SEC 1
J 0
(-2175 4250);
DISPLAY 0.914894 (-2175 4250);
PAINT MONO (-2175 4250);
DISPLAY INVISIBLE (-2175 4250);
FORCEPROP 1 LAST PATH I42
J 0
(-2175 4200);
DISPLAY 0.978723 (-2175 4200);
PAINT WHITE (-2175 4200);
DISPLAY INVISIBLE (-2175 4200);
FORCEPROP 2 LAST ROOM SB_DECOUPLING
J 0
(-2225 4050);
PAINT WHITE (-2225 4050);
DISPLAY INVISIBLE (-2225 4050);
FORCEADD CAP_A..1
(-2625 4050);
FORCEPROP 1 LAST LOCATION C3N2
J 0
(-2575 4150);
DISPLAY 0.617021 (-2575 4150);
PAINT AQUA (-2575 4150);
FORCEPROP 1 LAST PART_NUMBER D97712-004
J 0
(-2575 3900);
DISPLAY 0.617021 (-2575 3900);
PAINT BLUE (-2575 3900);
FORCEPROP 1 LAST VALUE 1.0UF
J 0
(-2575 4100);
DISPLAY 0.617021 (-2575 4100);
PAINT SKYBLUE (-2575 4100);
FORCEPROP 1 LAST TOLERANCE 10%
J 0
(-2575 4000);
DISPLAY 0.617021 (-2575 4000);
PAINT SKYBLUE (-2575 4000);
FORCEPROP 1 LAST PACK_TYPE 0402V
J 0
(-2575 3850);
DISPLAY 0.617021 (-2575 3850);
PAINT SKYBLUE (-2575 3850);
FORCEPROP 1 LAST VOLTAGE 6.3V
J 0
(-2575 4050);
DISPLAY 0.617021 (-2575 4050);
PAINT SKYBLUE (-2575 4050);
FORCEPROP 1 LAST MATERIAL X6S
J 0
(-2575 3950);
DISPLAY 0.617021 (-2575 3950);
PAINT SKYBLUE (-2575 3950);
FORCEPROP 1 LASTPIN (-2625 4150) $PN 1
J 0
(-2615 4130);
DISPLAY 0.617021 (-2615 4130);
PAINT WHITE (-2615 4130);
FORCEPROP 1 LASTPIN (-2625 3950) $PN 2
J 0
(-2615 3930);
DISPLAY 0.617021 (-2615 3930);
PAINT WHITE (-2615 3930);
FORCEPROP 2 LAST CDS_LOCATION C3N2
J 0
(-2575 4150);
DISPLAY 0.617021 (-2575 4150);
PAINT AQUA (-2575 4150);
DISPLAY INVISIBLE (-2575 4150);
FORCEPROP 2 LAST BOM_COST SB
J 0
(-2575 3800);
PAINT MONO (-2575 3800);
DISPLAY INVISIBLE (-2575 3800);
FORCEPROP 2 LAST CDS_LIB dev_discrete
J 0
(-2625 4050);
PAINT ORANGE (-2625 4050);
DISPLAY INVISIBLE (-2625 4050);
FORCEPROP 2 LAST CDS_SEC 1
J 0
(-2575 4250);
DISPLAY 1.361702 (-2575 4250);
PAINT ORANGE (-2575 4250);
DISPLAY INVISIBLE (-2575 4250);
FORCEPROP 2 LAST $SEC 1
J 0
(-2575 4250);
DISPLAY 0.914894 (-2575 4250);
PAINT MONO (-2575 4250);
DISPLAY INVISIBLE (-2575 4250);
FORCEPROP 1 LAST PATH I43
J 0
(-2575 4200);
DISPLAY 0.978723 (-2575 4200);
PAINT WHITE (-2575 4200);
DISPLAY INVISIBLE (-2575 4200);
FORCEPROP 2 LAST ROOM SB_DECOUPLING
J 0
(-2625 4050);
PAINT WHITE (-2625 4050);
DISPLAY INVISIBLE (-2625 4050);
FORCEADD CAP_A..1
(-2200 3025);
FORCEPROP 1 LAST LOCATION C3N6
J 0
(-2150 3125);
DISPLAY 0.617021 (-2150 3125);
PAINT AQUA (-2150 3125);
FORCEPROP 1 LAST PART_NUMBER D97712-004
J 0
(-2150 2875);
DISPLAY 0.617021 (-2150 2875);
PAINT BLUE (-2150 2875);
FORCEPROP 1 LAST VALUE 1.0UF
J 0
(-2150 3075);
DISPLAY 0.617021 (-2150 3075);
PAINT SKYBLUE (-2150 3075);
FORCEPROP 1 LAST TOLERANCE 10%
J 0
(-2150 2975);
DISPLAY 0.617021 (-2150 2975);
PAINT SKYBLUE (-2150 2975);
FORCEPROP 1 LAST PACK_TYPE 0402V
J 0
(-2150 2825);
DISPLAY 0.617021 (-2150 2825);
PAINT SKYBLUE (-2150 2825);
FORCEPROP 1 LAST VOLTAGE 6.3V
J 0
(-2150 3025);
DISPLAY 0.617021 (-2150 3025);
PAINT SKYBLUE (-2150 3025);
FORCEPROP 1 LAST MATERIAL X6S
J 0
(-2150 2925);
DISPLAY 0.617021 (-2150 2925);
PAINT SKYBLUE (-2150 2925);
FORCEPROP 1 LASTPIN (-2200 3125) $PN 1
J 0
(-2190 3105);
DISPLAY 0.617021 (-2190 3105);
PAINT WHITE (-2190 3105);
FORCEPROP 1 LASTPIN (-2200 2925) $PN 2
J 0
(-2190 2905);
DISPLAY 0.617021 (-2190 2905);
PAINT WHITE (-2190 2905);
FORCEPROP 2 LAST CDS_LOCATION C3N6
J 0
(-2150 3125);
DISPLAY 0.617021 (-2150 3125);
PAINT AQUA (-2150 3125);
DISPLAY INVISIBLE (-2150 3125);
FORCEPROP 2 LAST BOM_COST SB
J 0
(-2150 2775);
PAINT MONO (-2150 2775);
DISPLAY INVISIBLE (-2150 2775);
FORCEPROP 2 LAST CDS_LIB dev_discrete
J 0
(-2200 3025);
PAINT ORANGE (-2200 3025);
DISPLAY INVISIBLE (-2200 3025);
FORCEPROP 2 LAST CDS_SEC 1
J 0
(-2150 3225);
DISPLAY 1.361702 (-2150 3225);
PAINT ORANGE (-2150 3225);
DISPLAY INVISIBLE (-2150 3225);
FORCEPROP 2 LAST $SEC 1
J 0
(-2150 3225);
DISPLAY 0.914894 (-2150 3225);
PAINT MONO (-2150 3225);
DISPLAY INVISIBLE (-2150 3225);
FORCEPROP 1 LAST PATH I44
J 0
(-2150 3175);
DISPLAY 0.978723 (-2150 3175);
PAINT WHITE (-2150 3175);
DISPLAY INVISIBLE (-2150 3175);
FORCEPROP 2 LAST ROOM SB_DECOUPLING
J 0
(-2200 3025);
PAINT WHITE (-2200 3025);
DISPLAY INVISIBLE (-2200 3025);
FORCEADD CAP_A..1
(-2600 3025);
FORCEPROP 1 LAST LOCATION C3N17
J 0
(-2550 3125);
DISPLAY 0.617021 (-2550 3125);
PAINT AQUA (-2550 3125);
FORCEPROP 1 LAST PART_NUMBER D97712-004
J 0
(-2550 2875);
DISPLAY 0.617021 (-2550 2875);
PAINT BLUE (-2550 2875);
FORCEPROP 1 LAST VALUE 1.0UF
J 0
(-2550 3075);
DISPLAY 0.617021 (-2550 3075);
PAINT SKYBLUE (-2550 3075);
FORCEPROP 1 LAST TOLERANCE 10%
J 0
(-2550 2975);
DISPLAY 0.617021 (-2550 2975);
PAINT SKYBLUE (-2550 2975);
FORCEPROP 1 LAST PACK_TYPE 0402V
J 0
(-2550 2825);
DISPLAY 0.617021 (-2550 2825);
PAINT SKYBLUE (-2550 2825);
FORCEPROP 1 LAST VOLTAGE 6.3V
J 0
(-2550 3025);
DISPLAY 0.617021 (-2550 3025);
PAINT SKYBLUE (-2550 3025);
FORCEPROP 1 LAST MATERIAL X6S
J 0
(-2550 2925);
DISPLAY 0.617021 (-2550 2925);
PAINT SKYBLUE (-2550 2925);
FORCEPROP 1 LASTPIN (-2600 3125) $PN 1
J 0
(-2590 3105);
DISPLAY 0.617021 (-2590 3105);
PAINT WHITE (-2590 3105);
FORCEPROP 1 LASTPIN (-2600 2925) $PN 2
J 0
(-2590 2905);
DISPLAY 0.617021 (-2590 2905);
PAINT WHITE (-2590 2905);
FORCEPROP 2 LAST CDS_LOCATION C3N17
J 0
(-2550 3125);
DISPLAY 0.617021 (-2550 3125);
PAINT AQUA (-2550 3125);
DISPLAY INVISIBLE (-2550 3125);
FORCEPROP 2 LAST BOM_COST SB
J 0
(-2550 2775);
PAINT MONO (-2550 2775);
DISPLAY INVISIBLE (-2550 2775);
FORCEPROP 2 LAST CDS_LIB dev_discrete
J 0
(-2600 3025);
PAINT ORANGE (-2600 3025);
DISPLAY INVISIBLE (-2600 3025);
FORCEPROP 2 LAST CDS_SEC 1
J 0
(-2550 3225);
DISPLAY 1.361702 (-2550 3225);
PAINT ORANGE (-2550 3225);
DISPLAY INVISIBLE (-2550 3225);
FORCEPROP 2 LAST $SEC 1
J 0
(-2550 3225);
DISPLAY 0.914894 (-2550 3225);
PAINT MONO (-2550 3225);
DISPLAY INVISIBLE (-2550 3225);
FORCEPROP 1 LAST PATH I45
J 0
(-2550 3175);
DISPLAY 0.978723 (-2550 3175);
PAINT WHITE (-2550 3175);
DISPLAY INVISIBLE (-2550 3175);
FORCEPROP 2 LAST ROOM SB_DECOUPLING
J 0
(-2600 3025);
PAINT WHITE (-2600 3025);
DISPLAY INVISIBLE (-2600 3025);
FORCEADD CAP_A..1
(-3000 4050);
FORCEPROP 1 LAST PART_NUMBER D97712-004
J 0
(-2950 3900);
DISPLAY 0.617021 (-2950 3900);
PAINT BLUE (-2950 3900);
FORCEPROP 1 LAST LOCATION C3N4
J 0
(-2950 4150);
DISPLAY 0.617021 (-2950 4150);
PAINT AQUA (-2950 4150);
FORCEPROP 1 LAST VALUE 1.0UF
J 0
(-2950 4100);
DISPLAY 0.617021 (-2950 4100);
PAINT SKYBLUE (-2950 4100);
FORCEPROP 1 LAST TOLERANCE 10%
J 0
(-2950 4000);
DISPLAY 0.617021 (-2950 4000);
PAINT SKYBLUE (-2950 4000);
FORCEPROP 1 LAST PACK_TYPE 0402V
J 0
(-2950 3850);
DISPLAY 0.617021 (-2950 3850);
PAINT SKYBLUE (-2950 3850);
FORCEPROP 1 LAST VOLTAGE 6.3V
J 0
(-2950 4050);
DISPLAY 0.617021 (-2950 4050);
PAINT SKYBLUE (-2950 4050);
FORCEPROP 1 LAST MATERIAL X6S
J 0
(-2950 3950);
DISPLAY 0.617021 (-2950 3950);
PAINT SKYBLUE (-2950 3950);
FORCEPROP 1 LASTPIN (-3000 4150) $PN 1
J 0
(-2990 4130);
DISPLAY 0.617021 (-2990 4130);
PAINT WHITE (-2990 4130);
FORCEPROP 1 LASTPIN (-3000 3950) $PN 2
J 0
(-2990 3930);
DISPLAY 0.617021 (-2990 3930);
PAINT WHITE (-2990 3930);
FORCEPROP 2 LAST CDS_LOCATION C3N4
J 0
(-2950 4150);
DISPLAY 0.617021 (-2950 4150);
PAINT AQUA (-2950 4150);
DISPLAY INVISIBLE (-2950 4150);
FORCEPROP 2 LAST BOM_COST SB
J 0
(-2950 3800);
PAINT MONO (-2950 3800);
DISPLAY INVISIBLE (-2950 3800);
FORCEPROP 2 LAST CDS_LIB dev_discrete
J 0
(-3000 4050);
PAINT ORANGE (-3000 4050);
DISPLAY INVISIBLE (-3000 4050);
FORCEPROP 2 LAST CDS_SEC 1
J 0
(-2950 4250);
DISPLAY 1.361702 (-2950 4250);
PAINT ORANGE (-2950 4250);
DISPLAY INVISIBLE (-2950 4250);
FORCEPROP 2 LAST $SEC 1
J 0
(-2950 4250);
DISPLAY 0.914894 (-2950 4250);
PAINT MONO (-2950 4250);
DISPLAY INVISIBLE (-2950 4250);
FORCEPROP 1 LAST PATH I46
J 0
(-2950 4200);
DISPLAY 0.978723 (-2950 4200);
PAINT WHITE (-2950 4200);
DISPLAY INVISIBLE (-2950 4200);
FORCEPROP 2 LAST ROOM SB_DECOUPLING
J 0
(-3000 4050);
PAINT WHITE (-3000 4050);
DISPLAY INVISIBLE (-3000 4050);
FORCEADD PVNN_PCH_STBY..1
(-3225 4300);
FORCEPROP 3 LASTPIN (-3225 4250) SIG_NAME PVNN_PCH_STBY\g
J 0
(-3215 4260);
DISPLAY 0.659574 (-3215 4260);
PAINT MONO (-3215 4260);
DISPLAY INVISIBLE (-3215 4260);
FORCEPROP 1 LAST VOLTAGE 1.0V
J 0
(-3270 4257);
DISPLAY 0.340426 (-3270 4257);
PAINT SKYBLUE (-3270 4257);
DISPLAY INVISIBLE (-3270 4257);
FORCEPROP 2 LAST CDS_LIB mstr_symbols
J 0
(-3225 4300);
PAINT ORANGE (-3225 4300);
DISPLAY INVISIBLE (-3225 4300);
FORCEPROP 2 LAST BOM_COST SB
J 0
(-3225 4450);
PAINT MONO (-3225 4450);
DISPLAY INVISIBLE (-3225 4450);
FORCEPROP 1 LAST PATH I47
J 0
(-3175 4325);
DISPLAY 0.872340 (-3175 4325);
PAINT AQUA (-3175 4325);
DISPLAY INVISIBLE (-3175 4325);
FORCEPROP 2 LAST ROOM SB_DECOUPLING
J 0
(-3225 4400);
DISPLAY 1.361702 (-3225 4400);
PAINT WHITE (-3225 4400);
DISPLAY INVISIBLE (-3225 4400);
FORCEPROP 1 LAST BODY_TYPE PLUMBING
J 0
(-3270 4257);
DISPLAY 0.340426 (-3270 4257);
PAINT GREEN (-3270 4257);
DISPLAY INVISIBLE (-3270 4257);
FORCEPROP 1 LAST HDL_POWER PVNN_PCH_STBY
J 1
(-3225 4350);
DISPLAY 0.872340 (-3225 4350);
PAINT GREEN (-3225 4350);
DISPLAY INVISIBLE (-3225 4350);
FORCEADD CAP_A..1
(-3400 4050);
FORCEPROP 1 LAST LOCATION C3N5
J 0
(-3350 4150);
DISPLAY 0.617021 (-3350 4150);
PAINT AQUA (-3350 4150);
FORCEPROP 1 LAST PART_NUMBER D97712-004
J 0
(-3350 3900);
DISPLAY 0.617021 (-3350 3900);
PAINT BLUE (-3350 3900);
FORCEPROP 1 LAST VALUE 1.0UF
J 0
(-3350 4100);
DISPLAY 0.617021 (-3350 4100);
PAINT SKYBLUE (-3350 4100);
FORCEPROP 1 LAST TOLERANCE 10%
J 0
(-3350 4000);
DISPLAY 0.617021 (-3350 4000);
PAINT SKYBLUE (-3350 4000);
FORCEPROP 1 LAST PACK_TYPE 0402V
J 0
(-3350 3850);
DISPLAY 0.617021 (-3350 3850);
PAINT SKYBLUE (-3350 3850);
FORCEPROP 1 LAST VOLTAGE 6.3V
J 0
(-3350 4050);
DISPLAY 0.617021 (-3350 4050);
PAINT SKYBLUE (-3350 4050);
FORCEPROP 1 LAST MATERIAL X6S
J 0
(-3350 3950);
DISPLAY 0.617021 (-3350 3950);
PAINT SKYBLUE (-3350 3950);
FORCEPROP 1 LASTPIN (-3400 4150) $PN 1
J 0
(-3390 4130);
DISPLAY 0.617021 (-3390 4130);
PAINT WHITE (-3390 4130);
FORCEPROP 1 LASTPIN (-3400 3950) $PN 2
J 0
(-3390 3930);
DISPLAY 0.617021 (-3390 3930);
PAINT WHITE (-3390 3930);
FORCEPROP 2 LAST CDS_LOCATION C3N5
J 0
(-3350 4150);
DISPLAY 0.617021 (-3350 4150);
PAINT AQUA (-3350 4150);
DISPLAY INVISIBLE (-3350 4150);
FORCEPROP 2 LAST BOM_COST SB
J 0
(-3350 3800);
PAINT MONO (-3350 3800);
DISPLAY INVISIBLE (-3350 3800);
FORCEPROP 2 LAST CDS_LIB dev_discrete
J 0
(-3400 4050);
PAINT ORANGE (-3400 4050);
DISPLAY INVISIBLE (-3400 4050);
FORCEPROP 2 LAST CDS_SEC 1
J 0
(-3350 4250);
DISPLAY 1.361702 (-3350 4250);
PAINT ORANGE (-3350 4250);
DISPLAY INVISIBLE (-3350 4250);
FORCEPROP 2 LAST $SEC 1
J 0
(-3350 4250);
DISPLAY 0.914894 (-3350 4250);
PAINT MONO (-3350 4250);
DISPLAY INVISIBLE (-3350 4250);
FORCEPROP 1 LAST PATH I48
J 0
(-3350 4200);
DISPLAY 0.978723 (-3350 4200);
PAINT WHITE (-3350 4200);
DISPLAY INVISIBLE (-3350 4200);
FORCEPROP 2 LAST ROOM SB_DECOUPLING
J 0
(-3400 4050);
PAINT WHITE (-3400 4050);
DISPLAY INVISIBLE (-3400 4050);
FORCEADD CAP_A..1
(-2975 3025);
FORCEPROP 1 LAST LOCATION C3N15
J 0
(-2925 3125);
DISPLAY 0.617021 (-2925 3125);
PAINT AQUA (-2925 3125);
FORCEPROP 1 LAST PART_NUMBER D97712-004
J 0
(-2925 2875);
DISPLAY 0.617021 (-2925 2875);
PAINT BLUE (-2925 2875);
FORCEPROP 1 LAST VALUE 1.0UF
J 0
(-2925 3075);
DISPLAY 0.617021 (-2925 3075);
PAINT SKYBLUE (-2925 3075);
FORCEPROP 1 LAST TOLERANCE 10%
J 0
(-2925 2975);
DISPLAY 0.617021 (-2925 2975);
PAINT SKYBLUE (-2925 2975);
FORCEPROP 1 LAST PACK_TYPE 0402V
J 0
(-2925 2825);
DISPLAY 0.617021 (-2925 2825);
PAINT SKYBLUE (-2925 2825);
FORCEPROP 1 LAST VOLTAGE 6.3V
J 0
(-2925 3025);
DISPLAY 0.617021 (-2925 3025);
PAINT SKYBLUE (-2925 3025);
FORCEPROP 1 LAST MATERIAL X6S
J 0
(-2925 2925);
DISPLAY 0.617021 (-2925 2925);
PAINT SKYBLUE (-2925 2925);
FORCEPROP 1 LASTPIN (-2975 3125) $PN 1
J 0
(-2965 3105);
DISPLAY 0.617021 (-2965 3105);
PAINT WHITE (-2965 3105);
FORCEPROP 1 LASTPIN (-2975 2925) $PN 2
J 0
(-2965 2905);
DISPLAY 0.617021 (-2965 2905);
PAINT WHITE (-2965 2905);
FORCEPROP 2 LAST CDS_LOCATION C3N15
J 0
(-2925 3125);
DISPLAY 0.617021 (-2925 3125);
PAINT AQUA (-2925 3125);
DISPLAY INVISIBLE (-2925 3125);
FORCEPROP 2 LAST BOM_COST SB
J 0
(-2925 2775);
PAINT MONO (-2925 2775);
DISPLAY INVISIBLE (-2925 2775);
FORCEPROP 2 LAST CDS_LIB dev_discrete
J 0
(-2975 3025);
PAINT ORANGE (-2975 3025);
DISPLAY INVISIBLE (-2975 3025);
FORCEPROP 2 LAST CDS_SEC 1
J 0
(-2925 3225);
DISPLAY 1.361702 (-2925 3225);
PAINT ORANGE (-2925 3225);
DISPLAY INVISIBLE (-2925 3225);
FORCEPROP 2 LAST $SEC 1
J 0
(-2925 3225);
DISPLAY 0.914894 (-2925 3225);
PAINT MONO (-2925 3225);
DISPLAY INVISIBLE (-2925 3225);
FORCEPROP 1 LAST PATH I49
J 0
(-2925 3175);
DISPLAY 0.978723 (-2925 3175);
PAINT WHITE (-2925 3175);
DISPLAY INVISIBLE (-2925 3175);
FORCEPROP 2 LAST ROOM SB_DECOUPLING
J 0
(-2975 3025);
PAINT WHITE (-2975 3025);
DISPLAY INVISIBLE (-2975 3025);
FORCEADD PVNN_PCH_STBY..1
(1350 4725);
FORCEPROP 3 LASTPIN (1350 4675) SIG_NAME PVNN_PCH_STBY\g
J 0
(1360 4685);
DISPLAY 0.659574 (1360 4685);
PAINT MONO (1360 4685);
DISPLAY INVISIBLE (1360 4685);
FORCEPROP 1 LAST VOLTAGE 1.0V
J 0
(1305 4682);
DISPLAY 0.340426 (1305 4682);
PAINT SKYBLUE (1305 4682);
DISPLAY INVISIBLE (1305 4682);
FORCEPROP 2 LAST CDS_LIB mstr_symbols
J 0
(1350 4725);
PAINT ORANGE (1350 4725);
DISPLAY INVISIBLE (1350 4725);
FORCEPROP 2 LAST BOM_COST SB
J 0
(1350 4825);
DISPLAY 1.361702 (1350 4825);
PAINT ORANGE (1350 4825);
DISPLAY INVISIBLE (1350 4825);
FORCEPROP 1 LAST PATH I5
J 0
(1400 4750);
DISPLAY 0.872340 (1400 4750);
PAINT AQUA (1400 4750);
DISPLAY INVISIBLE (1400 4750);
FORCEPROP 2 LAST ROOM SB_DECOUPLING
J 0
(1350 4825);
DISPLAY 1.361702 (1350 4825);
PAINT ORANGE (1350 4825);
DISPLAY INVISIBLE (1350 4825);
FORCEPROP 1 LAST BODY_TYPE PLUMBING
J 0
(1305 4682);
DISPLAY 0.340426 (1305 4682);
PAINT GREEN (1305 4682);
DISPLAY INVISIBLE (1305 4682);
FORCEPROP 1 LAST HDL_POWER PVNN_PCH_STBY
J 1
(1350 4775);
DISPLAY 0.872340 (1350 4775);
PAINT GREEN (1350 4775);
DISPLAY INVISIBLE (1350 4775);
FORCEADD PVNN_PCH_STBY..1
(-3200 3275);
FORCEPROP 3 LASTPIN (-3200 3225) SIG_NAME PVNN_PCH_STBY\g
J 0
(-3190 3235);
DISPLAY 0.659574 (-3190 3235);
PAINT MONO (-3190 3235);
DISPLAY INVISIBLE (-3190 3235);
FORCEPROP 1 LAST VOLTAGE 1.0V
J 0
(-3245 3232);
DISPLAY 0.340426 (-3245 3232);
PAINT SKYBLUE (-3245 3232);
DISPLAY INVISIBLE (-3245 3232);
FORCEPROP 2 LAST CDS_LIB mstr_symbols
J 0
(-3200 3275);
PAINT ORANGE (-3200 3275);
DISPLAY INVISIBLE (-3200 3275);
FORCEPROP 2 LAST BOM_COST SB
J 0
(-3200 3425);
PAINT MONO (-3200 3425);
DISPLAY INVISIBLE (-3200 3425);
FORCEPROP 1 LAST PATH I50
J 0
(-3150 3300);
DISPLAY 0.872340 (-3150 3300);
PAINT AQUA (-3150 3300);
DISPLAY INVISIBLE (-3150 3300);
FORCEPROP 2 LAST ROOM SB_DECOUPLING
J 0
(-3200 3375);
DISPLAY 1.361702 (-3200 3375);
PAINT WHITE (-3200 3375);
DISPLAY INVISIBLE (-3200 3375);
FORCEPROP 1 LAST BODY_TYPE PLUMBING
J 0
(-3245 3232);
DISPLAY 0.340426 (-3245 3232);
PAINT GREEN (-3245 3232);
DISPLAY INVISIBLE (-3245 3232);
FORCEPROP 1 LAST HDL_POWER PVNN_PCH_STBY
J 1
(-3200 3325);
DISPLAY 0.872340 (-3200 3325);
PAINT GREEN (-3200 3325);
DISPLAY INVISIBLE (-3200 3325);
FORCEADD CAP_A..1
(-3375 3025);
FORCEPROP 1 LAST LOCATION C3N20
J 0
(-3325 3125);
DISPLAY 0.617021 (-3325 3125);
PAINT AQUA (-3325 3125);
FORCEPROP 1 LAST PART_NUMBER D97712-004
J 0
(-3325 2875);
DISPLAY 0.617021 (-3325 2875);
PAINT BLUE (-3325 2875);
FORCEPROP 1 LAST VALUE 1.0UF
J 0
(-3325 3075);
DISPLAY 0.617021 (-3325 3075);
PAINT SKYBLUE (-3325 3075);
FORCEPROP 1 LAST TOLERANCE 10%
J 0
(-3325 2975);
DISPLAY 0.617021 (-3325 2975);
PAINT SKYBLUE (-3325 2975);
FORCEPROP 1 LAST PACK_TYPE 0402V
J 0
(-3325 2825);
DISPLAY 0.617021 (-3325 2825);
PAINT SKYBLUE (-3325 2825);
FORCEPROP 1 LAST VOLTAGE 6.3V
J 0
(-3325 3025);
DISPLAY 0.617021 (-3325 3025);
PAINT SKYBLUE (-3325 3025);
FORCEPROP 1 LAST MATERIAL X6S
J 0
(-3325 2925);
DISPLAY 0.617021 (-3325 2925);
PAINT SKYBLUE (-3325 2925);
FORCEPROP 1 LASTPIN (-3375 3125) $PN 1
J 0
(-3365 3105);
DISPLAY 0.617021 (-3365 3105);
PAINT WHITE (-3365 3105);
FORCEPROP 1 LASTPIN (-3375 2925) $PN 2
J 0
(-3365 2905);
DISPLAY 0.617021 (-3365 2905);
PAINT WHITE (-3365 2905);
FORCEPROP 2 LAST CDS_LOCATION C3N20
J 0
(-3325 3125);
DISPLAY 0.617021 (-3325 3125);
PAINT AQUA (-3325 3125);
DISPLAY INVISIBLE (-3325 3125);
FORCEPROP 2 LAST BOM_COST SB
J 0
(-3325 2775);
PAINT MONO (-3325 2775);
DISPLAY INVISIBLE (-3325 2775);
FORCEPROP 2 LAST CDS_LIB dev_discrete
J 0
(-3375 3025);
PAINT ORANGE (-3375 3025);
DISPLAY INVISIBLE (-3375 3025);
FORCEPROP 2 LAST CDS_SEC 1
J 0
(-3325 3225);
DISPLAY 1.361702 (-3325 3225);
PAINT ORANGE (-3325 3225);
DISPLAY INVISIBLE (-3325 3225);
FORCEPROP 2 LAST $SEC 1
J 0
(-3325 3225);
DISPLAY 0.914894 (-3325 3225);
PAINT MONO (-3325 3225);
DISPLAY INVISIBLE (-3325 3225);
FORCEPROP 1 LAST PATH I51
J 0
(-3325 3175);
DISPLAY 0.978723 (-3325 3175);
PAINT WHITE (-3325 3175);
DISPLAY INVISIBLE (-3325 3175);
FORCEPROP 2 LAST ROOM SB_DECOUPLING
J 0
(-3375 3025);
PAINT WHITE (-3375 3025);
DISPLAY INVISIBLE (-3375 3025);
FORCEADD CAP_A..1
(-2550 1925);
FORCEPROP 1 LAST LOCATION C3L23
J 0
(-2500 2025);
DISPLAY 0.617021 (-2500 2025);
PAINT AQUA (-2500 2025);
FORCEPROP 1 LAST PART_NUMBER E15431-004
J 0
(-2500 1775);
DISPLAY 0.617021 (-2500 1775);
PAINT BLUE (-2500 1775);
FORCEPROP 1 LAST VALUE 22.0UF
J 0
(-2500 1975);
DISPLAY 0.617021 (-2500 1975);
PAINT SKYBLUE (-2500 1975);
FORCEPROP 1 LAST TOLERANCE 20%
J 0
(-2500 1875);
DISPLAY 0.617021 (-2500 1875);
PAINT SKYBLUE (-2500 1875);
FORCEPROP 1 LAST PACK_TYPE 0603V
J 0
(-2500 1725);
DISPLAY 0.617021 (-2500 1725);
PAINT SKYBLUE (-2500 1725);
FORCEPROP 1 LAST VOLTAGE 4V
J 0
(-2500 1925);
DISPLAY 0.617021 (-2500 1925);
PAINT SKYBLUE (-2500 1925);
FORCEPROP 1 LAST MATERIAL X6S
J 0
(-2500 1825);
DISPLAY 0.617021 (-2500 1825);
PAINT SKYBLUE (-2500 1825);
FORCEPROP 1 LASTPIN (-2550 2025) $PN 1
J 0
(-2540 2005);
DISPLAY 0.617021 (-2540 2005);
PAINT ORANGE (-2540 2005);
FORCEPROP 1 LASTPIN (-2550 1825) $PN 2
J 0
(-2540 1805);
DISPLAY 0.617021 (-2540 1805);
PAINT ORANGE (-2540 1805);
FORCEPROP 2 LAST CDS_LOCATION C3L23
J 0
(-2500 2025);
DISPLAY 0.617021 (-2500 2025);
PAINT AQUA (-2500 2025);
DISPLAY INVISIBLE (-2500 2025);
FORCEPROP 2 LAST BOM_COST SB
J 0
(-2500 2125);
DISPLAY 1.361702 (-2500 2125);
PAINT ORANGE (-2500 2125);
DISPLAY INVISIBLE (-2500 2125);
FORCEPROP 2 LAST CDS_LIB dev_discrete
J 0
(-2550 1925);
PAINT ORANGE (-2550 1925);
DISPLAY INVISIBLE (-2550 1925);
FORCEPROP 2 LAST CDS_SEC 1
J 0
(-2500 2125);
PAINT MONO (-2500 2125);
DISPLAY INVISIBLE (-2500 2125);
FORCEPROP 2 LAST $SEC 1
J 0
(-2500 2125);
PAINT MONO (-2500 2125);
DISPLAY INVISIBLE (-2500 2125);
FORCEPROP 1 LAST PATH I52
J 0
(-2500 2075);
DISPLAY 0.978723 (-2500 2075);
PAINT WHITE (-2500 2075);
DISPLAY INVISIBLE (-2500 2075);
FORCEPROP 2 LAST ROOM SB_DECOUPLING
J 0
(-2500 2075);
DISPLAY 1.361702 (-2500 2075);
PAINT ORANGE (-2500 2075);
DISPLAY INVISIBLE (-2500 2075);
FORCEADD PVNN_PCH_STBY..1
(-3150 2200);
FORCEPROP 3 LASTPIN (-3150 2150) SIG_NAME PVNN_PCH_STBY\g
J 0
(-3140 2160);
DISPLAY 0.659574 (-3140 2160);
PAINT MONO (-3140 2160);
DISPLAY INVISIBLE (-3140 2160);
FORCEPROP 1 LAST VOLTAGE 1.0V
J 0
(-3195 2157);
DISPLAY 0.340426 (-3195 2157);
PAINT SKYBLUE (-3195 2157);
DISPLAY INVISIBLE (-3195 2157);
FORCEPROP 2 LAST CDS_LIB mstr_symbols
J 0
(-3150 2200);
PAINT ORANGE (-3150 2200);
DISPLAY INVISIBLE (-3150 2200);
FORCEPROP 2 LAST BOM_COST SB
J 0
(-3150 2300);
DISPLAY 1.361702 (-3150 2300);
PAINT ORANGE (-3150 2300);
DISPLAY INVISIBLE (-3150 2300);
FORCEPROP 1 LAST PATH I53
J 0
(-3100 2225);
DISPLAY 0.872340 (-3100 2225);
PAINT AQUA (-3100 2225);
DISPLAY INVISIBLE (-3100 2225);
FORCEPROP 2 LAST ROOM SB_DECOUPLING
J 0
(-3150 2300);
DISPLAY 1.361702 (-3150 2300);
PAINT ORANGE (-3150 2300);
DISPLAY INVISIBLE (-3150 2300);
FORCEPROP 1 LAST BODY_TYPE PLUMBING
J 0
(-3195 2157);
DISPLAY 0.340426 (-3195 2157);
PAINT GREEN (-3195 2157);
DISPLAY INVISIBLE (-3195 2157);
FORCEPROP 1 LAST HDL_POWER PVNN_PCH_STBY
J 1
(-3150 2250);
DISPLAY 0.872340 (-3150 2250);
PAINT GREEN (-3150 2250);
DISPLAY INVISIBLE (-3150 2250);
FORCEADD CAP_A..1
(-2950 1925);
FORCEPROP 1 LAST LOCATION C3L22
J 0
(-2900 2025);
DISPLAY 0.617021 (-2900 2025);
PAINT AQUA (-2900 2025);
FORCEPROP 1 LAST PART_NUMBER E15431-004
J 0
(-2900 1775);
DISPLAY 0.617021 (-2900 1775);
PAINT BLUE (-2900 1775);
FORCEPROP 1 LAST VALUE 22.0UF
J 0
(-2900 1975);
DISPLAY 0.617021 (-2900 1975);
PAINT SKYBLUE (-2900 1975);
FORCEPROP 1 LAST TOLERANCE 20%
J 0
(-2900 1875);
DISPLAY 0.617021 (-2900 1875);
PAINT SKYBLUE (-2900 1875);
FORCEPROP 1 LAST PACK_TYPE 0603V
J 0
(-2900 1725);
DISPLAY 0.617021 (-2900 1725);
PAINT SKYBLUE (-2900 1725);
FORCEPROP 1 LAST VOLTAGE 4V
J 0
(-2900 1925);
DISPLAY 0.617021 (-2900 1925);
PAINT SKYBLUE (-2900 1925);
FORCEPROP 1 LAST MATERIAL X6S
J 0
(-2900 1825);
DISPLAY 0.617021 (-2900 1825);
PAINT SKYBLUE (-2900 1825);
FORCEPROP 1 LASTPIN (-2950 2025) $PN 1
J 0
(-2940 2005);
DISPLAY 0.617021 (-2940 2005);
PAINT WHITE (-2940 2005);
FORCEPROP 1 LASTPIN (-2950 1825) $PN 2
J 0
(-2940 1805);
DISPLAY 0.617021 (-2940 1805);
PAINT WHITE (-2940 1805);
FORCEPROP 2 LAST CDS_LOCATION C3L22
J 0
(-2900 2025);
DISPLAY 0.617021 (-2900 2025);
PAINT AQUA (-2900 2025);
DISPLAY INVISIBLE (-2900 2025);
FORCEPROP 2 LAST BOM_COST SB
J 0
(-2900 2125);
DISPLAY 1.361702 (-2900 2125);
PAINT ORANGE (-2900 2125);
DISPLAY INVISIBLE (-2900 2125);
FORCEPROP 2 LAST CDS_LIB dev_discrete
J 0
(-2950 1925);
PAINT ORANGE (-2950 1925);
DISPLAY INVISIBLE (-2950 1925);
FORCEPROP 2 LAST CDS_SEC 1
J 0
(-2900 2125);
DISPLAY 1.361702 (-2900 2125);
PAINT ORANGE (-2900 2125);
DISPLAY INVISIBLE (-2900 2125);
FORCEPROP 2 LAST $SEC 1
J 0
(-2900 2125);
DISPLAY 0.914894 (-2900 2125);
PAINT MONO (-2900 2125);
DISPLAY INVISIBLE (-2900 2125);
FORCEPROP 1 LAST PATH I54
J 0
(-2900 2075);
DISPLAY 0.978723 (-2900 2075);
PAINT WHITE (-2900 2075);
DISPLAY INVISIBLE (-2900 2075);
FORCEPROP 2 LAST ROOM SB_DECOUPLING
J 0
(-2900 2075);
DISPLAY 1.361702 (-2900 2075);
PAINT ORANGE (-2900 2075);
DISPLAY INVISIBLE (-2900 2075);
FORCEADD GND..1
(-3100 1600);
FORCEPROP 3 LASTPIN (-3100 1650) SIG_NAME GND\g
J 0
(-3090 1660);
DISPLAY 0.659574 (-3090 1660);
PAINT MONO (-3090 1660);
DISPLAY INVISIBLE (-3090 1660);
FORCEPROP 1 LAST VOLTAGE 0.0V
J 0
(-3145 1557);
DISPLAY 0.340426 (-3145 1557);
PAINT SKYBLUE (-3145 1557);
DISPLAY INVISIBLE (-3145 1557);
FORCEPROP 2 LAST CDS_LIB mstr_symbols
J 0
(-3100 1600);
PAINT MONO (-3100 1600);
DISPLAY INVISIBLE (-3100 1600);
FORCEPROP 1 LAST SIZE 1B
J 0
(-3025 1550);
DISPLAY 1.170213 (-3025 1550);
PAINT AQUA (-3025 1550);
DISPLAY INVISIBLE (-3025 1550);
FORCEPROP 2 LAST BOM_COST SB
J 0
(-3075 1675);
DISPLAY 1.361702 (-3075 1675);
PAINT ORANGE (-3075 1675);
DISPLAY INVISIBLE (-3075 1675);
FORCEPROP 1 LAST PATH I55
J 0
(-3025 1600);
DISPLAY 0.872340 (-3025 1600);
PAINT AQUA (-3025 1600);
DISPLAY INVISIBLE (-3025 1600);
FORCEPROP 2 LAST ROOM SB_DECOUPLING
J 0
(-3075 1675);
DISPLAY 1.361702 (-3075 1675);
PAINT ORANGE (-3075 1675);
DISPLAY INVISIBLE (-3075 1675);
FORCEPROP 1 LAST BODY_TYPE PLUMBING
J 0
(-3145 1557);
DISPLAY 0.340426 (-3145 1557);
PAINT GREEN (-3145 1557);
DISPLAY INVISIBLE (-3145 1557);
FORCEPROP 1 LAST HDL_POWER GND
J 0
(-3100 1750);
DISPLAY 1.170213 (-3100 1750);
PAINT GREEN (-3100 1750);
DISPLAY INVISIBLE (-3100 1750);
FORCEADD CAP_A..1
(-3425 1925);
FORCEPROP 1 LAST LOCATION C3L24
J 0
(-3375 2025);
DISPLAY 0.617021 (-3375 2025);
PAINT AQUA (-3375 2025);
FORCEPROP 1 LAST PART_NUMBER E15431-004
J 0
(-3375 1775);
DISPLAY 0.617021 (-3375 1775);
PAINT BLUE (-3375 1775);
FORCEPROP 1 LAST VALUE 22.0UF
J 0
(-3375 1975);
DISPLAY 0.617021 (-3375 1975);
PAINT SKYBLUE (-3375 1975);
FORCEPROP 1 LAST TOLERANCE 20%
J 0
(-3375 1875);
DISPLAY 0.617021 (-3375 1875);
PAINT SKYBLUE (-3375 1875);
FORCEPROP 1 LAST PACK_TYPE 0603V
J 0
(-3375 1725);
DISPLAY 0.617021 (-3375 1725);
PAINT SKYBLUE (-3375 1725);
FORCEPROP 1 LAST VOLTAGE 4V
J 0
(-3375 1925);
DISPLAY 0.617021 (-3375 1925);
PAINT SKYBLUE (-3375 1925);
FORCEPROP 1 LAST MATERIAL X6S
J 0
(-3375 1825);
DISPLAY 0.617021 (-3375 1825);
PAINT SKYBLUE (-3375 1825);
FORCEPROP 1 LASTPIN (-3425 2025) $PN 1
J 0
(-3415 2005);
DISPLAY 0.617021 (-3415 2005);
PAINT WHITE (-3415 2005);
FORCEPROP 1 LASTPIN (-3425 1825) $PN 2
J 0
(-3415 1805);
DISPLAY 0.617021 (-3415 1805);
PAINT WHITE (-3415 1805);
FORCEPROP 2 LAST CDS_LOCATION C3L24
J 0
(-3375 2025);
DISPLAY 0.617021 (-3375 2025);
PAINT AQUA (-3375 2025);
DISPLAY INVISIBLE (-3375 2025);
FORCEPROP 2 LAST BOM_COST SB
J 0
(-3375 2125);
DISPLAY 1.361702 (-3375 2125);
PAINT ORANGE (-3375 2125);
DISPLAY INVISIBLE (-3375 2125);
FORCEPROP 2 LAST CDS_LIB dev_discrete
J 0
(-3425 1925);
PAINT ORANGE (-3425 1925);
DISPLAY INVISIBLE (-3425 1925);
FORCEPROP 2 LAST CDS_SEC 1
J 0
(-3375 2125);
DISPLAY 1.361702 (-3375 2125);
PAINT ORANGE (-3375 2125);
DISPLAY INVISIBLE (-3375 2125);
FORCEPROP 2 LAST $SEC 1
J 0
(-3375 2125);
DISPLAY 0.914894 (-3375 2125);
PAINT MONO (-3375 2125);
DISPLAY INVISIBLE (-3375 2125);
FORCEPROP 1 LAST PATH I56
J 0
(-3375 2075);
DISPLAY 0.978723 (-3375 2075);
PAINT WHITE (-3375 2075);
DISPLAY INVISIBLE (-3375 2075);
FORCEPROP 2 LAST ROOM SB_DECOUPLING
J 0
(-3375 2075);
DISPLAY 1.361702 (-3375 2075);
PAINT ORANGE (-3375 2075);
DISPLAY INVISIBLE (-3375 2075);
FORCEADD CAP_A..1
(1075 4475);
FORCEPROP 1 LAST LOCATION C3M6
J 0
(1125 4575);
DISPLAY 0.617021 (1125 4575);
PAINT AQUA (1125 4575);
FORCEPROP 1 LAST PART_NUMBER E15431-004
J 0
(1125 4325);
DISPLAY 0.617021 (1125 4325);
PAINT BLUE (1125 4325);
FORCEPROP 1 LAST VALUE 22.0UF
J 0
(1125 4525);
DISPLAY 0.617021 (1125 4525);
PAINT SKYBLUE (1125 4525);
FORCEPROP 1 LAST TOLERANCE 20%
J 0
(1125 4425);
DISPLAY 0.617021 (1125 4425);
PAINT SKYBLUE (1125 4425);
FORCEPROP 1 LAST PACK_TYPE 0603V
J 0
(1125 4275);
DISPLAY 0.617021 (1125 4275);
PAINT SKYBLUE (1125 4275);
FORCEPROP 1 LAST VOLTAGE 4V
J 0
(1125 4475);
DISPLAY 0.617021 (1125 4475);
PAINT SKYBLUE (1125 4475);
FORCEPROP 1 LAST MATERIAL X6S
J 0
(1125 4375);
DISPLAY 0.617021 (1125 4375);
PAINT SKYBLUE (1125 4375);
FORCEPROP 1 LASTPIN (1075 4575) $PN 1
J 0
(1085 4555);
DISPLAY 0.617021 (1085 4555);
PAINT WHITE (1085 4555);
FORCEPROP 1 LASTPIN (1075 4375) $PN 2
J 0
(1085 4355);
DISPLAY 0.617021 (1085 4355);
PAINT WHITE (1085 4355);
FORCEPROP 2 LAST CDS_LOCATION C3M6
J 0
(1125 4575);
DISPLAY 0.617021 (1125 4575);
PAINT AQUA (1125 4575);
DISPLAY INVISIBLE (1125 4575);
FORCEPROP 2 LAST BOM_COST SB
J 0
(1125 4675);
DISPLAY 1.361702 (1125 4675);
PAINT ORANGE (1125 4675);
DISPLAY INVISIBLE (1125 4675);
FORCEPROP 2 LAST CDS_LIB dev_discrete
J 0
(1075 4475);
PAINT ORANGE (1075 4475);
DISPLAY INVISIBLE (1075 4475);
FORCEPROP 2 LAST CDS_SEC 1
J 0
(1125 4675);
DISPLAY 1.361702 (1125 4675);
PAINT ORANGE (1125 4675);
DISPLAY INVISIBLE (1125 4675);
FORCEPROP 2 LAST $SEC 1
J 0
(1125 4675);
DISPLAY 0.914894 (1125 4675);
PAINT MONO (1125 4675);
DISPLAY INVISIBLE (1125 4675);
FORCEPROP 1 LAST PATH I6
J 0
(1125 4625);
DISPLAY 0.978723 (1125 4625);
PAINT WHITE (1125 4625);
DISPLAY INVISIBLE (1125 4625);
FORCEPROP 2 LAST ROOM SB_DECOUPLING
J 0
(1125 4625);
DISPLAY 1.361702 (1125 4625);
PAINT ORANGE (1125 4625);
DISPLAY INVISIBLE (1125 4625);
FORCEADD CAP_A..1
(2550 3500);
FORCEPROP 1 LAST LOCATION C7C9
J 0
(2600 3600);
DISPLAY 0.617021 (2600 3600);
PAINT AQUA (2600 3600);
FORCEPROP 1 LAST PART_NUMBER E15431-004
J 0
(2600 3350);
DISPLAY 0.617021 (2600 3350);
PAINT BLUE (2600 3350);
FORCEPROP 1 LAST VALUE 22.0UF
J 0
(2600 3550);
DISPLAY 0.617021 (2600 3550);
PAINT SKYBLUE (2600 3550);
FORCEPROP 1 LAST TOLERANCE 20%
J 0
(2600 3450);
DISPLAY 0.617021 (2600 3450);
PAINT SKYBLUE (2600 3450);
FORCEPROP 1 LAST PACK_TYPE 0603V
J 0
(2600 3300);
DISPLAY 0.617021 (2600 3300);
PAINT SKYBLUE (2600 3300);
FORCEPROP 1 LAST VOLTAGE 4V
J 0
(2600 3500);
DISPLAY 0.617021 (2600 3500);
PAINT SKYBLUE (2600 3500);
FORCEPROP 1 LAST MATERIAL X6S
J 0
(2600 3400);
DISPLAY 0.617021 (2600 3400);
PAINT SKYBLUE (2600 3400);
FORCEPROP 2 LAST CDS_LOCATION C7C9
J 0
(2600 3600);
DISPLAY 0.617021 (2600 3600);
PAINT AQUA (2600 3600);
DISPLAY INVISIBLE (2600 3600);
FORCEPROP 2 LAST BOM_COST SB
J 0
(2600 3250);
PAINT MONO (2600 3250);
DISPLAY INVISIBLE (2600 3250);
FORCEPROP 2 LAST CDS_LIB dev_discrete
J 0
(2550 3500);
PAINT ORANGE (2550 3500);
DISPLAY INVISIBLE (2550 3500);
FORCEPROP 2 LAST CDS_SEC 1
J 0
(2600 3700);
DISPLAY 1.361702 (2600 3700);
PAINT ORANGE (2600 3700);
DISPLAY INVISIBLE (2600 3700);
FORCEPROP 2 LAST $SEC 1
J 0
(2600 3700);
DISPLAY 0.914894 (2600 3700);
PAINT MONO (2600 3700);
DISPLAY INVISIBLE (2600 3700);
FORCEPROP 1 LAST PATH I7
J 0
(2600 3650);
DISPLAY 0.978723 (2600 3650);
PAINT WHITE (2600 3650);
DISPLAY INVISIBLE (2600 3650);
FORCEPROP 2 LAST ROOM SB_DECOUPLING
J 0
(2550 3500);
PAINT WHITE (2550 3500);
DISPLAY INVISIBLE (2550 3500);
FORCEPROP 1 LASTPIN (2550 3600) $PN 1
J 0
(2560 3580);
DISPLAY 1.063830 (2560 3580);
PAINT WHITE (2560 3580);
DISPLAY INVISIBLE (2560 3580);
FORCEPROP 1 LASTPIN (2550 3400) $PN 2
J 0
(2560 3380);
DISPLAY 1.063830 (2560 3380);
PAINT WHITE (2560 3380);
DISPLAY INVISIBLE (2560 3380);
FORCEADD CAP_A..1
(2600 2525);
FORCEPROP 1 LAST LOCATION C3N27
J 0
(2650 2625);
DISPLAY 0.617021 (2650 2625);
PAINT AQUA (2650 2625);
FORCEPROP 1 LAST PART_NUMBER E15431-004
J 0
(2650 2375);
DISPLAY 0.617021 (2650 2375);
PAINT BLUE (2650 2375);
FORCEPROP 1 LAST VALUE 22.0UF
J 0
(2650 2575);
DISPLAY 0.617021 (2650 2575);
PAINT SKYBLUE (2650 2575);
FORCEPROP 1 LAST TOLERANCE 20%
J 0
(2650 2475);
DISPLAY 0.617021 (2650 2475);
PAINT SKYBLUE (2650 2475);
FORCEPROP 1 LAST PACK_TYPE 0603V
J 0
(2650 2325);
DISPLAY 0.617021 (2650 2325);
PAINT SKYBLUE (2650 2325);
FORCEPROP 1 LAST VOLTAGE 4V
J 0
(2650 2525);
DISPLAY 0.617021 (2650 2525);
PAINT SKYBLUE (2650 2525);
FORCEPROP 1 LAST MATERIAL X6S
J 0
(2650 2425);
DISPLAY 0.617021 (2650 2425);
PAINT SKYBLUE (2650 2425);
FORCEPROP 2 LAST CDS_LOCATION C3N27
J 0
(2650 2625);
DISPLAY 0.617021 (2650 2625);
PAINT AQUA (2650 2625);
DISPLAY INVISIBLE (2650 2625);
FORCEPROP 2 LAST BOM_COST SB
J 0
(2650 2275);
PAINT MONO (2650 2275);
DISPLAY INVISIBLE (2650 2275);
FORCEPROP 2 LAST CDS_LIB dev_discrete
J 0
(2600 2525);
PAINT ORANGE (2600 2525);
DISPLAY INVISIBLE (2600 2525);
FORCEPROP 2 LAST CDS_SEC 1
J 0
(2650 2725);
DISPLAY 1.361702 (2650 2725);
PAINT ORANGE (2650 2725);
DISPLAY INVISIBLE (2650 2725);
FORCEPROP 2 LAST $SEC 1
J 0
(2650 2725);
DISPLAY 0.914894 (2650 2725);
PAINT MONO (2650 2725);
DISPLAY INVISIBLE (2650 2725);
FORCEPROP 1 LAST PATH I8
J 0
(2650 2675);
DISPLAY 0.978723 (2650 2675);
PAINT WHITE (2650 2675);
DISPLAY INVISIBLE (2650 2675);
FORCEPROP 2 LAST ROOM SB_DECOUPLING
J 0
(2600 2525);
PAINT WHITE (2600 2525);
DISPLAY INVISIBLE (2600 2525);
FORCEPROP 1 LASTPIN (2600 2625) $PN 1
J 0
(2610 2605);
DISPLAY 1.063830 (2610 2605);
PAINT WHITE (2610 2605);
DISPLAY INVISIBLE (2610 2605);
FORCEPROP 1 LASTPIN (2600 2425) $PN 2
J 0
(2610 2405);
DISPLAY 1.063830 (2610 2405);
PAINT WHITE (2610 2405);
DISPLAY INVISIBLE (2610 2405);
FORCEADD CAP_A..1
(2225 2525);
FORCEPROP 1 LAST LOCATION C3N30
J 0
(2275 2625);
DISPLAY 0.617021 (2275 2625);
PAINT AQUA (2275 2625);
FORCEPROP 1 LAST PART_NUMBER E15431-004
J 0
(2275 2375);
DISPLAY 0.617021 (2275 2375);
PAINT BLUE (2275 2375);
FORCEPROP 1 LAST VALUE 22.0UF
J 0
(2275 2575);
DISPLAY 0.617021 (2275 2575);
PAINT SKYBLUE (2275 2575);
FORCEPROP 1 LAST TOLERANCE 20%
J 0
(2275 2475);
DISPLAY 0.617021 (2275 2475);
PAINT SKYBLUE (2275 2475);
FORCEPROP 1 LAST VOLTAGE 4V
J 0
(2275 2525);
DISPLAY 0.617021 (2275 2525);
PAINT SKYBLUE (2275 2525);
FORCEPROP 1 LAST MATERIAL X6S
J 0
(2275 2425);
DISPLAY 0.617021 (2275 2425);
PAINT SKYBLUE (2275 2425);
FORCEPROP 1 LAST PACK_TYPE 0603V
J 0
(2275 2325);
DISPLAY 0.617021 (2275 2325);
PAINT SKYBLUE (2275 2325);
FORCEPROP 2 LAST CDS_LOCATION C3N30
J 0
(2275 2625);
DISPLAY 0.617021 (2275 2625);
PAINT AQUA (2275 2625);
DISPLAY INVISIBLE (2275 2625);
FORCEPROP 2 LAST BOM_COST SB
J 0
(2275 2275);
PAINT MONO (2275 2275);
DISPLAY INVISIBLE (2275 2275);
FORCEPROP 2 LAST CDS_LIB dev_discrete
J 0
(2225 2525);
PAINT ORANGE (2225 2525);
DISPLAY INVISIBLE (2225 2525);
FORCEPROP 2 LAST CDS_SEC 1
J 0
(2275 2725);
DISPLAY 1.361702 (2275 2725);
PAINT ORANGE (2275 2725);
DISPLAY INVISIBLE (2275 2725);
FORCEPROP 2 LAST $SEC 1
J 0
(2275 2725);
DISPLAY 0.914894 (2275 2725);
PAINT MONO (2275 2725);
DISPLAY INVISIBLE (2275 2725);
FORCEPROP 1 LAST PATH I9
J 0
(2275 2675);
DISPLAY 0.978723 (2275 2675);
PAINT WHITE (2275 2675);
DISPLAY INVISIBLE (2275 2675);
FORCEPROP 2 LAST ROOM SB_DECOUPLING
J 0
(2225 2525);
PAINT WHITE (2225 2525);
DISPLAY INVISIBLE (2225 2525);
FORCEPROP 1 LASTPIN (2225 2625) $PN 1
J 0
(2235 2605);
DISPLAY 1.063830 (2235 2605);
PAINT WHITE (2235 2605);
DISPLAY INVISIBLE (2235 2605);
FORCEPROP 1 LASTPIN (2225 2425) $PN 2
J 0
(2235 2405);
DISPLAY 1.063830 (2235 2405);
PAINT WHITE (2235 2405);
DISPLAY INVISIBLE (2235 2405);
FORCEADD CAD_NOTE..1
(-2575 2400);
FORCEPROP 0 LAST L2 STYLE NEAR TO PIN.
J 0
(-2725 2200);
DISPLAY 1.063830 (-2725 2200);
PAINT WHITE (-2725 2200);
FORCEPROP 0 LAST L1 PLACE CAPS BSC
J 0
(-2725 2275);
DISPLAY 1.063830 (-2725 2275);
PAINT WHITE (-2725 2275);
FORCEPROP 2 LAST CDS_LIB mstr_symbols
J 0
(-2575 2400);
PAINT ORANGE (-2575 2400);
DISPLAY INVISIBLE (-2575 2400);
FORCEPROP 2 LAST BOM_COST SB
J 0
(-2725 2350);
PAINT MONO (-2725 2350);
DISPLAY INVISIBLE (-2725 2350);
FORCEPROP 2 LAST ROOM SB_DECOUPLING
J 0
(-2725 2350);
PAINT WHITE (-2725 2350);
DISPLAY INVISIBLE (-2725 2350);
FORCEPROP 1 LAST COMMENT_BODY TRUE
J 0
(-2550 2500);
DISPLAY 1.319149 (-2550 2500);
PAINT GREEN (-2550 2500);
DISPLAY INVISIBLE (-2550 2500);
FORCEADD CAD_NOTE..1
(675 975);
FORCEPROP 0 LAST L1 PLACE CAPS ON THE
J 0
(525 850);
DISPLAY 1.063830 (525 850);
PAINT WHITE (525 850);
FORCEPROP 0 LAST L2 EDGE OF THE PKG.
J 0
(525 775);
DISPLAY 1.063830 (525 775);
PAINT WHITE (525 775);
FORCEPROP 2 LAST BOM_COST SB
J 0
(525 925);
PAINT MONO (525 925);
DISPLAY INVISIBLE (525 925);
FORCEPROP 2 LAST CDS_LIB mstr_symbols
J 0
(675 975);
PAINT ORANGE (675 975);
DISPLAY INVISIBLE (675 975);
FORCEPROP 2 LAST ROOM SB_DECOUPLING
J 0
(525 925);
PAINT WHITE (525 925);
DISPLAY INVISIBLE (525 925);
FORCEPROP 1 LAST COMMENT_BODY TRUE
J 0
(700 1075);
DISPLAY 1.319149 (700 1075);
PAINT GREEN (700 1075);
DISPLAY INVISIBLE (700 1075);
FORCEADD INTEL_CORP_BPAGE..1
(4250 200);
FORCEPROP 1 LAST CDS_CON_LAST_MODIFIED Fri Jun 16 17:48:50 2017
J 0
(2825 525);
PAINT ORANGE (2825 525);
DISPLAY INVISIBLE (2825 525);
FORCEPROP 1 LAST CUSTOM_TXT_CDS <CURRENT_DESIGN_SHEET> OF <TOTAL_DESIGN_SHEETS>
J 0
(3750 225);
PAINT ORANGE (3750 225);
FORCEPROP 1 LAST CUSTOM_TXT_CDS <CON_LAST_MODIFIED>
J 0
(250 300);
PAINT ORANGE (250 300);
FORCEPROP 2 LAST CUSTOM_TXT_CDS <XR_PAGE_TITLE>
J 0
(-3640 5450);
DISPLAY 0.638298 (-3640 5450);
PAINT PINK (-3640 5450);
DISPLAY INVISIBLE (-3640 5450);
FORCEPROP 1 LAST SCH_TITLE PCH DECOUPLING 3/3
J 0
(-3700 250);
DISPLAY 1.212766 (-3700 250);
PAINT ORANGE (-3700 250);
FORCEPROP 2 LAST CDS_LIB mstr_symbols
J 0
(4250 200);
PAINT MONO (4250 200);
DISPLAY INVISIBLE (4250 200);
FORCEPROP 2 LAST PAGE_BORDER TRUE
J 0
(-3640 5450);
DISPLAY 0.638298 (-3640 5450);
PAINT PINK (-3640 5450);
DISPLAY INVISIBLE (-3640 5450);
FORCEPROP 1 LAST COMMENT_BODY TRUE
J 0
(4262 212);
DISPLAY 0.468085 (4262 212);
PAINT GREEN (4262 212);
DISPLAY INVISIBLE (4262 212);
FORCEPROP 2 LAST CDS_XR_PAGE_TITLE CR-132 : @BASEBOARD_FAB2_LIB.BASEBOARD_FAB2(SCH_1):PAGE132
J 0
(-3640 5450);
DISPLAY 0.638298 (-3640 5450);
PAINT PINK (-3640 5450);
DISPLAY INVISIBLE (-3640 5450);
FORCEADD CAD_NOTE..1
(-1225 1225);
FORCEPROP 0 LAST L1 PLACE CAPS ON THE SECONDARY SIDE OF BGA
J 0
(-1375 1075);
DISPLAY 1.063830 (-1375 1075);
PAINT WHITE (-1375 1075);
FORCEPROP 0 LAST L2 
J 0
(-1375 1075);
DISPLAY 1.063830 (-1375 1075);
PAINT WHITE (-1375 1075);
FORCEPROP 2 LAST CDS_LIB mstr_symbols
J 0
(-1225 1225);
PAINT ORANGE (-1225 1225);
DISPLAY INVISIBLE (-1225 1225);
FORCEPROP 2 LAST BOM_COST SB
J 0
(-1375 1175);
PAINT MONO (-1375 1175);
DISPLAY INVISIBLE (-1375 1175);
FORCEPROP 2 LAST ROOM SB_DECOUPLING
J 0
(-1375 1175);
PAINT WHITE (-1375 1175);
DISPLAY INVISIBLE (-1375 1175);
FORCEPROP 1 LAST COMMENT_BODY TRUE
J 0
(-1200 1325);
DISPLAY 1.319149 (-1200 1325);
PAINT GREEN (-1200 1325);
DISPLAY INVISIBLE (-1200 1325);
FORCEADD DESIGN_NOTE..1
(-2675 1250);
FORCEPROP 0 LAST L2 
J 0
(-2900 1025);
DISPLAY 1.021277 (-2900 1025);
PAINT ORANGE (-2900 1025);
FORCEPROP 0 LAST L1 PVNN_PCH_STBY DECOUPLING CAPS
J 0
(-2875 1125);
DISPLAY 1.063830 (-2875 1125);
PAINT WHITE (-2875 1125);
FORCEPROP 2 LAST BOM_COST SB
J 0
(-2875 1175);
DISPLAY 1.361702 (-2875 1175);
PAINT ORANGE (-2875 1175);
DISPLAY INVISIBLE (-2875 1175);
FORCEPROP 2 LAST CDS_LIB mstr_symbols
J 0
(-2675 1250);
PAINT ORANGE (-2675 1250);
DISPLAY INVISIBLE (-2675 1250);
FORCEPROP 2 LAST ROOM SB_DECOUPLING
J 0
(-2875 1175);
DISPLAY 1.361702 (-2875 1175);
PAINT WHITE (-2875 1175);
DISPLAY INVISIBLE (-2875 1175);
FORCEPROP 1 LAST COMMENT_BODY TRUE
J 0
(-2650 1350);
DISPLAY 1.319149 (-2650 1350);
PAINT ORANGE (-2650 1350);
DISPLAY INVISIBLE (-2650 1350);
FORCEADD DESIGN_NOTE..1
(2350 1000);
FORCEPROP 0 LAST L1 PVNN_PCH_STBY DECOUPLING CAPS
J 0
(2150 875);
DISPLAY 1.063830 (2150 875);
PAINT WHITE (2150 875);
FORCEPROP 2 LAST CDS_LIB mstr_symbols
J 0
(2350 1000);
PAINT ORANGE (2350 1000);
DISPLAY INVISIBLE (2350 1000);
FORCEPROP 2 LAST BOM_COST SB
J 0
(2150 925);
DISPLAY 1.361702 (2150 925);
PAINT ORANGE (2150 925);
DISPLAY INVISIBLE (2150 925);
FORCEPROP 2 LAST ROOM SB_DECOUPLING
J 0
(2150 925);
DISPLAY 1.361702 (2150 925);
PAINT WHITE (2150 925);
DISPLAY INVISIBLE (2150 925);
FORCEPROP 1 LAST COMMENT_BODY TRUE
J 0
(2375 1100);
DISPLAY 1.319149 (2375 1100);
PAINT ORANGE (2375 1100);
DISPLAY INVISIBLE (2375 1100);
WIRE 16 -1 (2050 4250)(2050 4200);
WIRE 16 -1 (2050 4250)(1825 4250);
WIRE 16 -1 (2200 4250)(2050 4250);
WIRE 16 -1 (2575 4250)(2200 4250);
WIRE 16 -1 (2200 4375)(2200 4250);
WIRE 16 -1 (1825 4250)(1450 4250);
WIRE 16 -1 (1825 4375)(1825 4250);
WIRE 16 -1 (1450 4250)(1075 4250);
WIRE 16 -1 (1450 4375)(1450 4250);
WIRE 16 -1 (2575 4375)(2575 4250);
WIRE 16 -1 (1075 4375)(1075 4250);
WIRE 16 -1 (1350 3675)(1350 3700);
WIRE 16 -1 (1350 3675)(1450 3675);
WIRE 16 -1 (1350 3675)(1075 3675);
WIRE 16 -1 (1075 3600)(1075 3675);
WIRE 16 -1 (1825 3675)(1450 3675);
WIRE 16 -1 (1450 3600)(1450 3675);
WIRE 16 -1 (2200 3675)(1825 3675);
WIRE 16 -1 (1825 3600)(1825 3675);
WIRE 16 -1 (2550 3675)(2200 3675);
WIRE 16 -1 (2200 3600)(2200 3675);
WIRE 16 -1 (2550 3600)(2550 3675);
WIRE 16 -1 (2075 3275)(2075 3225);
WIRE 16 -1 (2075 3275)(1825 3275);
WIRE 16 -1 (2075 3275)(2200 3275);
WIRE 16 -1 (2550 3275)(2200 3275);
WIRE 16 -1 (2200 3400)(2200 3275);
WIRE 16 -1 (1825 3275)(1450 3275);
WIRE 16 -1 (1825 3400)(1825 3275);
WIRE 16 -1 (1075 3275)(1450 3275);
WIRE 16 -1 (1450 3400)(1450 3275);
WIRE 16 -1 (2550 3400)(2550 3275);
WIRE 16 -1 (1075 3400)(1075 3275);
WIRE 16 -1 (1400 2700)(1400 2725);
WIRE 16 -1 (1400 2700)(1475 2700);
WIRE 16 -1 (1400 2700)(1100 2700);
WIRE 16 -1 (1100 2625)(1100 2700);
WIRE 16 -1 (1850 2700)(1475 2700);
WIRE 16 -1 (1475 2625)(1475 2700);
WIRE 16 -1 (2225 2700)(1850 2700);
WIRE 16 -1 (1850 2625)(1850 2700);
WIRE 16 -1 (2600 2700)(2225 2700);
WIRE 16 -1 (2225 2625)(2225 2700);
WIRE 16 -1 (2600 2625)(2600 2700);
WIRE 16 -1 (2050 2300)(2050 2250);
WIRE 16 -1 (2050 2300)(1850 2300);
WIRE 16 -1 (2050 2300)(2225 2300);
WIRE 16 -1 (2600 2300)(2225 2300);
WIRE 16 -1 (2225 2425)(2225 2300);
WIRE 16 -1 (1850 2300)(1475 2300);
WIRE 16 -1 (1850 2425)(1850 2300);
WIRE 16 -1 (1100 2300)(1475 2300);
WIRE 16 -1 (1475 2425)(1475 2300);
WIRE 16 -1 (2600 2425)(2600 2300);
WIRE 16 -1 (1100 2425)(1100 2300);
WIRE 16 -1 (1925 1825)(1925 1775);
WIRE 16 -1 (2150 1775)(1925 1775);
WIRE 16 -1 (1925 1775)(1700 1775);
WIRE 16 -1 (1700 1675)(1700 1775);
WIRE 16 -1 (2150 1675)(2150 1775);
WIRE 16 -1 (1925 1325)(1925 1250);
WIRE 16 -1 (2150 1325)(1925 1325);
WIRE 16 -1 (1925 1325)(1700 1325);
WIRE 16 -1 (1700 1475)(1700 1325);
WIRE 16 -1 (2150 1475)(2150 1325);
WIRE 16 -1 (-1750 3825)(-1750 3800);
WIRE 16 -1 (-1850 3825)(-1750 3825);
WIRE 16 -1 (-1750 3825)(-1475 3825);
WIRE 16 -1 (-1475 3825)(-1100 3825);
WIRE 16 -1 (-1475 3950)(-1475 3825);
WIRE 16 -1 (-1850 3825)(-2225 3825);
WIRE 16 -1 (-1850 3950)(-1850 3825);
WIRE 16 -1 (-2225 3825)(-2625 3825);
WIRE 16 -1 (-2225 3950)(-2225 3825);
WIRE 16 -1 (-725 3825)(-1100 3825);
WIRE 16 -1 (-1100 3950)(-1100 3825);
WIRE 16 -1 (-325 3825)(-725 3825);
WIRE 16 -1 (-725 3950)(-725 3825);
WIRE 16 -1 (-2625 3825)(-3000 3825);
WIRE 16 -1 (-2625 3950)(-2625 3825);
WIRE 16 -1 (-3400 3825)(-3000 3825);
WIRE 16 -1 (-3000 3950)(-3000 3825);
WIRE 16 -1 (-325 3950)(-325 3825);
WIRE 16 -1 (-3400 3950)(-3400 3825);
WIRE 16 -1 (-1725 2800)(-1725 2775);
WIRE 16 -1 (-1825 2800)(-1725 2800);
WIRE 16 -1 (-1725 2800)(-1450 2800);
WIRE 16 -1 (-1450 2800)(-1075 2800);
WIRE 16 -1 (-1450 2925)(-1450 2800);
WIRE 16 -1 (-1825 2800)(-2200 2800);
WIRE 16 -1 (-1825 2925)(-1825 2800);
WIRE 16 -1 (-2200 2800)(-2600 2800);
WIRE 16 -1 (-2200 2925)(-2200 2800);
WIRE 16 -1 (-700 2800)(-1075 2800);
WIRE 16 -1 (-1075 2925)(-1075 2800);
WIRE 16 -1 (-300 2800)(-700 2800);
WIRE 16 -1 (-700 2925)(-700 2800);
WIRE 16 -1 (-2600 2800)(-2975 2800);
WIRE 16 -1 (-2600 2925)(-2600 2800);
WIRE 16 -1 (-3375 2800)(-2975 2800);
WIRE 16 -1 (-2975 2925)(-2975 2800);
WIRE 16 -1 (-300 2925)(-300 2800);
WIRE 16 -1 (-3375 2925)(-3375 2800);
WIRE 16 -1 (-875 2150)(-875 2100);
WIRE 16 -1 (-650 2100)(-875 2100);
WIRE 16 -1 (-875 2100)(-1100 2100);
WIRE 16 -1 (-1100 2000)(-1100 2100);
WIRE 16 -1 (-650 2000)(-650 2100);
WIRE 16 -1 (-875 1650)(-875 1575);
WIRE 16 -1 (-650 1650)(-875 1650);
WIRE 16 -1 (-875 1650)(-1100 1650);
WIRE 16 -1 (-1100 1800)(-1100 1650);
WIRE 16 -1 (-650 1800)(-650 1650);
WIRE 16 -1 (1350 4675)(1350 4625);
WIRE 16 -1 (1450 4625)(1350 4625);
WIRE 16 -1 (1075 4625)(1350 4625);
WIRE 16 -1 (1075 4575)(1075 4625);
WIRE 16 -1 (1825 4625)(1450 4625);
WIRE 16 -1 (1450 4575)(1450 4625);
WIRE 16 -1 (2200 4625)(1825 4625);
WIRE 16 -1 (1825 4575)(1825 4625);
WIRE 16 -1 (2575 4625)(2200 4625);
WIRE 16 -1 (2200 4575)(2200 4625);
WIRE 16 -1 (2575 4625)(2575 4575);
WIRE 16 -1 (-3200 3200)(-3200 3225);
WIRE 16 -1 (-3200 3200)(-2975 3200);
WIRE 16 -1 (-3375 3200)(-3200 3200);
WIRE 16 -1 (-3375 3125)(-3375 3200);
WIRE 16 -1 (-2600 3200)(-2975 3200);
WIRE 16 -1 (-2975 3125)(-2975 3200);
WIRE 16 -1 (-2200 3200)(-2600 3200);
WIRE 16 -1 (-2600 3125)(-2600 3200);
WIRE 16 -1 (-1825 3200)(-2200 3200);
WIRE 16 -1 (-2200 3125)(-2200 3200);
WIRE 16 -1 (-1825 3200)(-1450 3200);
WIRE 16 -1 (-1825 3125)(-1825 3200);
WIRE 16 -1 (-1075 3200)(-1450 3200);
WIRE 16 -1 (-1450 3125)(-1450 3200);
WIRE 16 -1 (-1075 3200)(-700 3200);
WIRE 16 -1 (-1075 3125)(-1075 3200);
WIRE 16 -1 (-700 3200)(-300 3200);
WIRE 16 -1 (-700 3125)(-700 3200);
WIRE 16 -1 (-300 3200)(-300 3125);
WIRE 16 -1 (-3150 2150)(-3150 2100);
WIRE 16 -1 (-2950 2100)(-3150 2100);
WIRE 16 -1 (-3425 2100)(-3150 2100);
WIRE 16 -1 (-3425 2025)(-3425 2100);
WIRE 16 -1 (-2950 2100)(-2550 2100);
WIRE 16 -1 (-2950 2025)(-2950 2100);
WIRE 16 -1 (-2550 2100)(-2550 2025);
WIRE 16 -1 (-3100 1700)(-3100 1650);
WIRE 16 -1 (-3100 1700)(-2950 1700);
WIRE 16 -1 (-3100 1700)(-3425 1700);
WIRE 16 -1 (-3425 1825)(-3425 1700);
WIRE 16 -1 (-2550 1700)(-2950 1700);
WIRE 16 -1 (-2950 1825)(-2950 1700);
WIRE 16 -1 (-2550 1825)(-2550 1700);
WIRE 16 -1 (-3225 4225)(-3225 4250);
WIRE 16 -1 (-3225 4225)(-3000 4225);
WIRE 16 -1 (-3400 4225)(-3225 4225);
WIRE 16 -1 (-3400 4150)(-3400 4225);
WIRE 16 -1 (-2625 4225)(-3000 4225);
WIRE 16 -1 (-3000 4150)(-3000 4225);
WIRE 16 -1 (-2225 4225)(-2625 4225);
WIRE 16 -1 (-2625 4150)(-2625 4225);
WIRE 16 -1 (-1850 4225)(-2225 4225);
WIRE 16 -1 (-2225 4150)(-2225 4225);
WIRE 16 -1 (-1850 4225)(-1475 4225);
WIRE 16 -1 (-1850 4150)(-1850 4225);
WIRE 16 -1 (-1100 4225)(-1475 4225);
WIRE 16 -1 (-1475 4150)(-1475 4225);
WIRE 16 -1 (-1100 4225)(-725 4225);
WIRE 16 -1 (-1100 4150)(-1100 4225);
WIRE 16 -1 (-725 4225)(-325 4225);
WIRE 16 -1 (-725 4150)(-725 4225);
WIRE 16 -1 (-325 4225)(-325 4150);
WIRE 16 273 (225 5125)(225 650);
DOT 1 (-3000 3825);
DOT 1 (-3000 4225);
DOT 1 (2200 4625);
DOT 1 (1825 4625);
DOT 1 (1450 4625);
DOT 1 (1350 4625);
DOT 1 (2225 2700);
DOT 1 (2225 2300);
DOT 1 (2200 4250);
DOT 1 (2050 4250);
DOT 1 (1825 4250);
DOT 1 (2200 3675);
DOT 1 (1825 3675);
DOT 1 (1450 4250);
DOT 1 (1450 3675);
DOT 1 (1350 3675);
DOT 1 (2200 3275);
DOT 1 (2075 3275);
DOT 1 (1825 3275);
DOT 1 (1850 2700);
DOT 1 (1450 3275);
DOT 1 (1475 2700);
DOT 1 (1400 2700);
DOT 1 (1475 2300);
DOT 1 (1850 2300);
DOT 1 (2050 2300);
DOT 1 (1925 1775);
DOT 1 (1925 1325);
DOT 1 (-725 4225);
DOT 1 (-725 3825);
DOT 1 (-700 3200);
DOT 1 (-700 2800);
DOT 1 (-1100 4225);
DOT 1 (-1100 3825);
DOT 1 (-1475 4225);
DOT 1 (-1850 4225);
DOT 1 (-1475 3825);
DOT 1 (-1750 3825);
DOT 1 (-1850 3825);
DOT 1 (-1075 3200);
DOT 1 (-1075 2800);
DOT 1 (-1450 3200);
DOT 1 (-1825 3200);
DOT 1 (-1450 2800);
DOT 1 (-1725 2800);
DOT 1 (-1825 2800);
DOT 1 (-875 2100);
DOT 1 (-2225 4225);
DOT 1 (-2225 3825);
DOT 1 (-2625 4225);
DOT 1 (-2625 3825);
DOT 1 (-2200 3200);
DOT 1 (-2600 3200);
DOT 1 (-2600 2800);
DOT 1 (-2975 3200);
DOT 1 (-3200 3200);
DOT 1 (-2975 2800);
DOT 1 (-3100 1700);
DOT 1 (-875 1650);
DOT 1 (-2200 2800);
DOT 1 (-2950 1700);
DOT 1 (-3150 2100);
DOT 1 (-2950 2100);
DOT 1 (-3225 4225);
FORCENOTE
ROOM=SB_DECOUPLING
(-3450 475) 0;
DISPLAY LEFT (-3450 475);
DISPLAY 1.723404 (-3450 475);
PAINT PURPLE (-3450 475);
FORCENOTE
BOM_COST=SB
(-1775 475) 0;
DISPLAY LEFT (-1775 475);
DISPLAY 1.723404 (-1775 475);
PAINT PURPLE (-1775 475);
QUIT
